FILE_TYPE = MACRO_DRAWING;
SET COLOR_WIRE YELLOW;
SET COLOR_PROP ORANGE;
SET COLOR_DOT WHITE;
SET COLOR_ARC YELLOW;
SET COLOR_BODY GREEN;
SET COLOR_NOTE PURPLE;
SET PROP_DISPLAY VALUE;
SET PAGE_NUMBER P16;
FORCEADD GENOA_SP5..7
(-4700 3675);
FORCEPROP 1 LAST LOCATION U25
J 0
(-5345 6506);
DISPLAY 0.489362 (-5345 6506);
PAINT SKYBLUE (-5345 6506);
FORCEPROP 0 LAST $SEC 7
J 0
(-5325 6550);
DISPLAY 0.680851 (-5325 6550);
PAINT MONO (-5325 6550);
DISPLAY INVISIBLE (-5325 6550);
FORCEPROP 0 LAST CDS_SEC 7
J 0
(-5325 6525);
DISPLAY 1.021277 (-5325 6525);
DISPLAY INVISIBLE (-5325 6525);
FORCEPROP 0 LASTPIN (-5500 3050) $PN BC2
J 2
(-5510 3060);
DISPLAY 0.489362 (-5510 3060);
PAINT MONO (-5510 3060);
FORCEPROP 0 LASTPIN (-5500 3000) $PN BD2
J 2
(-5510 3010);
DISPLAY 0.489362 (-5510 3010);
PAINT MONO (-5510 3010);
FORCEPROP 0 LASTPIN (-5500 1900) $PN BF2
J 2
(-5510 1910);
DISPLAY 0.489362 (-5510 1910);
PAINT MONO (-5510 1910);
FORCEPROP 0 LASTPIN (-5500 1850) $PN BG2
J 2
(-5510 1860);
DISPLAY 0.489362 (-5510 1860);
PAINT MONO (-5510 1860);
FORCEPROP 0 LASTPIN (-5500 2200) $PN AR2
J 2
(-5510 2210);
DISPLAY 0.489362 (-5510 2210);
PAINT MONO (-5510 2210);
FORCEPROP 0 LASTPIN (-5500 2100) $PN AT2
J 2
(-5510 2110);
DISPLAY 0.489362 (-5510 2110);
PAINT MONO (-5510 2110);
FORCEPROP 0 LASTPIN (-5500 2900) $PN AU2
J 2
(-5510 2910);
DISPLAY 0.489362 (-5510 2910);
PAINT MONO (-5510 2910);
FORCEPROP 0 LASTPIN (-5500 2850) $PN AV4
J 2
(-5510 2860);
DISPLAY 0.489362 (-5510 2860);
PAINT MONO (-5510 2860);
FORCEPROP 0 LASTPIN (-5500 2750) $PN BN3
J 2
(-5510 2760);
DISPLAY 0.489362 (-5510 2760);
PAINT MONO (-5510 2760);
FORCEPROP 0 LASTPIN (-5500 1750) $PN AV2
J 2
(-5510 1760);
DISPLAY 0.489362 (-5510 1760);
PAINT MONO (-5510 1760);
FORCEPROP 0 LASTPIN (-5500 1700) $PN AW3
J 2
(-5510 1710);
DISPLAY 0.489362 (-5510 1710);
PAINT MONO (-5510 1710);
FORCEPROP 0 LASTPIN (-5500 1600) $PN BP4
J 2
(-5510 1610);
DISPLAY 0.489362 (-5510 1610);
PAINT MONO (-5510 1610);
FORCEPROP 0 LASTPIN (-5500 3900) $PN AW2
J 2
(-5510 3910);
DISPLAY 0.489362 (-5510 3910);
PAINT MONO (-5510 3910);
FORCEPROP 0 LASTPIN (-5500 3850) $PN AY2
J 2
(-5510 3860);
DISPLAY 0.489362 (-5510 3860);
PAINT MONO (-5510 3860);
FORCEPROP 0 LASTPIN (-5500 3800) $PN AY4
J 2
(-5510 3810);
DISPLAY 0.489362 (-5510 3810);
PAINT MONO (-5510 3810);
FORCEPROP 0 LASTPIN (-5500 3750) $PN BA3
J 2
(-5510 3760);
DISPLAY 0.489362 (-5510 3760);
PAINT MONO (-5510 3760);
FORCEPROP 0 LASTPIN (-5500 3700) $PN BA2
J 2
(-5510 3710);
DISPLAY 0.489362 (-5510 3710);
PAINT MONO (-5510 3710);
FORCEPROP 0 LASTPIN (-5500 3650) $PN BB2
J 2
(-5510 3660);
DISPLAY 0.489362 (-5510 3660);
PAINT MONO (-5510 3660);
FORCEPROP 0 LASTPIN (-5500 3600) $PN BB4
J 2
(-5510 3610);
DISPLAY 0.489362 (-5510 3610);
PAINT MONO (-5510 3610);
FORCEPROP 0 LASTPIN (-3900 2450) $PN AJ2
J 0
(-3890 2460);
DISPLAY 0.489362 (-3890 2460);
PAINT MONO (-3890 2460);
FORCEPROP 0 LASTPIN (-3900 2400) $PN AK4
J 0
(-3890 2410);
DISPLAY 0.489362 (-3890 2410);
PAINT MONO (-3890 2410);
FORCEPROP 0 LASTPIN (-3900 2350) $PN AK2
J 0
(-3890 2360);
DISPLAY 0.489362 (-3890 2360);
PAINT MONO (-3890 2360);
FORCEPROP 0 LASTPIN (-3900 2300) $PN AL3
J 0
(-3890 2310);
DISPLAY 0.489362 (-3890 2310);
PAINT MONO (-3890 2310);
FORCEPROP 0 LASTPIN (-3900 2250) $PN AN2
J 0
(-3890 2260);
DISPLAY 0.489362 (-3890 2260);
PAINT MONO (-3890 2260);
FORCEPROP 0 LASTPIN (-3900 2200) $PN AP4
J 0
(-3890 2210);
DISPLAY 0.489362 (-3890 2210);
PAINT MONO (-3890 2210);
FORCEPROP 0 LASTPIN (-3900 2150) $PN AP2
J 0
(-3890 2160);
DISPLAY 0.489362 (-3890 2160);
PAINT MONO (-3890 2160);
FORCEPROP 0 LASTPIN (-3900 2100) $PN AR3
J 0
(-3890 2110);
DISPLAY 0.489362 (-3890 2110);
PAINT MONO (-3890 2110);
FORCEPROP 0 LASTPIN (-3900 6050) $PN E2
J 0
(-3890 6060);
DISPLAY 0.489362 (-3890 6060);
PAINT MONO (-3890 6060);
FORCEPROP 0 LASTPIN (-3900 6000) $PN F4
J 0
(-3890 6010);
DISPLAY 0.489362 (-3890 6010);
PAINT MONO (-3890 6010);
FORCEPROP 0 LASTPIN (-3900 5950) $PN F2
J 0
(-3890 5960);
DISPLAY 0.489362 (-3890 5960);
PAINT MONO (-3890 5960);
FORCEPROP 0 LASTPIN (-3900 5900) $PN G3
J 0
(-3890 5910);
DISPLAY 0.489362 (-3890 5910);
PAINT MONO (-3890 5910);
FORCEPROP 0 LASTPIN (-3900 5850) $PN J2
J 0
(-3890 5860);
DISPLAY 0.489362 (-3890 5860);
PAINT MONO (-3890 5860);
FORCEPROP 0 LASTPIN (-3900 5800) $PN K4
J 0
(-3890 5810);
DISPLAY 0.489362 (-3890 5810);
PAINT MONO (-3890 5810);
FORCEPROP 0 LASTPIN (-3900 5750) $PN K2
J 0
(-3890 5760);
DISPLAY 0.489362 (-3890 5760);
PAINT MONO (-3890 5760);
FORCEPROP 0 LASTPIN (-3900 5700) $PN L3
J 0
(-3890 5710);
DISPLAY 0.489362 (-3890 5710);
PAINT MONO (-3890 5710);
FORCEPROP 0 LASTPIN (-3900 5600) $PN L2
J 0
(-3890 5610);
DISPLAY 0.489362 (-3890 5610);
PAINT MONO (-3890 5610);
FORCEPROP 0 LASTPIN (-3900 5550) $PN M4
J 0
(-3890 5560);
DISPLAY 0.489362 (-3890 5560);
PAINT MONO (-3890 5560);
FORCEPROP 0 LASTPIN (-3900 5500) $PN M2
J 0
(-3890 5510);
DISPLAY 0.489362 (-3890 5510);
PAINT MONO (-3890 5510);
FORCEPROP 0 LASTPIN (-3900 5450) $PN N3
J 0
(-3890 5460);
DISPLAY 0.489362 (-3890 5460);
PAINT MONO (-3890 5460);
FORCEPROP 0 LASTPIN (-3900 5400) $PN R2
J 0
(-3890 5410);
DISPLAY 0.489362 (-3890 5410);
PAINT MONO (-3890 5410);
FORCEPROP 0 LASTPIN (-3900 5350) $PN T4
J 0
(-3890 5360);
DISPLAY 0.489362 (-3890 5360);
PAINT MONO (-3890 5360);
FORCEPROP 0 LASTPIN (-3900 5300) $PN T2
J 0
(-3890 5310);
DISPLAY 0.489362 (-3890 5310);
PAINT MONO (-3890 5310);
FORCEPROP 0 LASTPIN (-3900 5250) $PN U3
J 0
(-3890 5260);
DISPLAY 0.489362 (-3890 5260);
PAINT MONO (-3890 5260);
FORCEPROP 0 LASTPIN (-3900 5150) $PN U2
J 0
(-3890 5160);
DISPLAY 0.489362 (-3890 5160);
PAINT MONO (-3890 5160);
FORCEPROP 0 LASTPIN (-3900 5100) $PN V4
J 0
(-3890 5110);
DISPLAY 0.489362 (-3890 5110);
PAINT MONO (-3890 5110);
FORCEPROP 0 LASTPIN (-3900 5050) $PN V2
J 0
(-3890 5060);
DISPLAY 0.489362 (-3890 5060);
PAINT MONO (-3890 5060);
FORCEPROP 0 LASTPIN (-3900 5000) $PN W3
J 0
(-3890 5010);
DISPLAY 0.489362 (-3890 5010);
PAINT MONO (-3890 5010);
FORCEPROP 0 LASTPIN (-3900 4950) $PN AA2
J 0
(-3890 4960);
DISPLAY 0.489362 (-3890 4960);
PAINT MONO (-3890 4960);
FORCEPROP 0 LASTPIN (-3900 4900) $PN AB4
J 0
(-3890 4910);
DISPLAY 0.489362 (-3890 4910);
PAINT MONO (-3890 4910);
FORCEPROP 0 LASTPIN (-3900 4850) $PN AB2
J 0
(-3890 4860);
DISPLAY 0.489362 (-3890 4860);
PAINT MONO (-3890 4860);
FORCEPROP 0 LASTPIN (-3900 4800) $PN AC3
J 0
(-3890 4810);
DISPLAY 0.489362 (-3890 4810);
PAINT MONO (-3890 4810);
FORCEPROP 0 LASTPIN (-3900 4700) $PN AC2
J 0
(-3890 4710);
DISPLAY 0.489362 (-3890 4710);
PAINT MONO (-3890 4710);
FORCEPROP 0 LASTPIN (-3900 4650) $PN AD4
J 0
(-3890 4660);
DISPLAY 0.489362 (-3890 4660);
PAINT MONO (-3890 4660);
FORCEPROP 0 LASTPIN (-3900 4600) $PN AD2
J 0
(-3890 4610);
DISPLAY 0.489362 (-3890 4610);
PAINT MONO (-3890 4610);
FORCEPROP 0 LASTPIN (-3900 4550) $PN AE3
J 0
(-3890 4560);
DISPLAY 0.489362 (-3890 4560);
PAINT MONO (-3890 4560);
FORCEPROP 0 LASTPIN (-3900 4500) $PN AG2
J 0
(-3890 4510);
DISPLAY 0.489362 (-3890 4510);
PAINT MONO (-3890 4510);
FORCEPROP 0 LASTPIN (-3900 4450) $PN AH4
J 0
(-3890 4460);
DISPLAY 0.489362 (-3890 4460);
PAINT MONO (-3890 4460);
FORCEPROP 0 LASTPIN (-3900 4400) $PN AH2
J 0
(-3890 4410);
DISPLAY 0.489362 (-3890 4410);
PAINT MONO (-3890 4410);
FORCEPROP 0 LASTPIN (-3900 4350) $PN AJ3
J 0
(-3890 4360);
DISPLAY 0.489362 (-3890 4360);
PAINT MONO (-3890 4360);
FORCEPROP 0 LASTPIN (-5500 6050) $PN G2
J 2
(-5510 6060);
DISPLAY 0.489362 (-5510 6060);
PAINT MONO (-5510 6060);
FORCEPROP 0 LASTPIN (-5500 5950) $PN N2
J 2
(-5510 5960);
DISPLAY 0.489362 (-5510 5960);
PAINT MONO (-5510 5960);
FORCEPROP 0 LASTPIN (-5500 5850) $PN W2
J 2
(-5510 5860);
DISPLAY 0.489362 (-5510 5860);
PAINT MONO (-5510 5860);
FORCEPROP 0 LASTPIN (-5500 5750) $PN AE2
J 2
(-5510 5760);
DISPLAY 0.489362 (-5510 5760);
PAINT MONO (-5510 5760);
FORCEPROP 0 LASTPIN (-5500 5650) $PN AL2
J 2
(-5510 5660);
DISPLAY 0.489362 (-5510 5660);
PAINT MONO (-5510 5660);
FORCEPROP 0 LASTPIN (-5500 5550) $PN J3
J 2
(-5510 5560);
DISPLAY 0.489362 (-5510 5560);
PAINT MONO (-5510 5560);
FORCEPROP 0 LASTPIN (-5500 5450) $PN R3
J 2
(-5510 5460);
DISPLAY 0.489362 (-5510 5460);
PAINT MONO (-5510 5460);
FORCEPROP 0 LASTPIN (-5500 5350) $PN AA3
J 2
(-5510 5360);
DISPLAY 0.489362 (-5510 5360);
PAINT MONO (-5510 5360);
FORCEPROP 0 LASTPIN (-5500 5250) $PN AG3
J 2
(-5510 5260);
DISPLAY 0.489362 (-5510 5260);
PAINT MONO (-5510 5260);
FORCEPROP 0 LASTPIN (-5500 5150) $PN AN3
J 2
(-5510 5160);
DISPLAY 0.489362 (-5510 5160);
PAINT MONO (-5510 5160);
FORCEPROP 0 LASTPIN (-5500 6000) $PN H2
J 2
(-5510 6010);
DISPLAY 0.489362 (-5510 6010);
PAINT MONO (-5510 6010);
FORCEPROP 0 LASTPIN (-5500 5900) $PN P2
J 2
(-5510 5910);
DISPLAY 0.489362 (-5510 5910);
PAINT MONO (-5510 5910);
FORCEPROP 0 LASTPIN (-5500 5800) $PN Y2
J 2
(-5510 5810);
DISPLAY 0.489362 (-5510 5810);
PAINT MONO (-5510 5810);
FORCEPROP 0 LASTPIN (-5500 5700) $PN AF2
J 2
(-5510 5710);
DISPLAY 0.489362 (-5510 5710);
PAINT MONO (-5510 5710);
FORCEPROP 0 LASTPIN (-5500 5600) $PN AM2
J 2
(-5510 5610);
DISPLAY 0.489362 (-5510 5610);
PAINT MONO (-5510 5610);
FORCEPROP 0 LASTPIN (-5500 5500) $PN H4
J 2
(-5510 5510);
DISPLAY 0.489362 (-5510 5510);
PAINT MONO (-5510 5510);
FORCEPROP 0 LASTPIN (-5500 5400) $PN P4
J 2
(-5510 5410);
DISPLAY 0.489362 (-5510 5410);
PAINT MONO (-5510 5410);
FORCEPROP 0 LASTPIN (-5500 5300) $PN Y4
J 2
(-5510 5310);
DISPLAY 0.489362 (-5510 5310);
PAINT MONO (-5510 5310);
FORCEPROP 0 LASTPIN (-5500 5200) $PN AF4
J 2
(-5510 5210);
DISPLAY 0.489362 (-5510 5210);
PAINT MONO (-5510 5210);
FORCEPROP 0 LASTPIN (-5500 5100) $PN AM4
J 2
(-5510 5110);
DISPLAY 0.489362 (-5510 5110);
PAINT MONO (-5510 5110);
FORCEPROP 0 LASTPIN (-5500 2650) $PN BC3
J 2
(-5510 2660);
DISPLAY 0.489362 (-5510 2660);
PAINT MONO (-5510 2660);
FORCEPROP 0 LASTPIN (-5500 2550) $PN BM4
J 2
(-5510 2560);
DISPLAY 0.489362 (-5510 2560);
PAINT MONO (-5510 2560);
FORCEPROP 0 LASTPIN (-5500 2500) $PN BN2
J 2
(-5510 2510);
DISPLAY 0.489362 (-5510 2510);
PAINT MONO (-5510 2510);
FORCEPROP 0 LASTPIN (-5500 2400) $PN BP2
J 2
(-5510 2410);
DISPLAY 0.489362 (-5510 2410);
PAINT MONO (-5510 2410);
FORCEPROP 0 LASTPIN (-5500 1500) $PN BL2
J 2
(-5510 1510);
DISPLAY 0.489362 (-5510 1510);
PAINT MONO (-5510 1510);
FORCEPROP 0 LASTPIN (-5500 1450) $PN BM2
J 2
(-5510 1460);
DISPLAY 0.489362 (-5510 1460);
PAINT MONO (-5510 1460);
FORCEPROP 0 LASTPIN (-5500 1350) $PN BR2
J 2
(-5510 1360);
DISPLAY 0.489362 (-5510 1360);
PAINT MONO (-5510 1360);
FORCEPROP 0 LASTPIN (-5500 3500) $PN BG3
J 2
(-5510 3510);
DISPLAY 0.489362 (-5510 3510);
PAINT MONO (-5510 3510);
FORCEPROP 0 LASTPIN (-5500 3450) $PN BH4
J 2
(-5510 3460);
DISPLAY 0.489362 (-5510 3460);
PAINT MONO (-5510 3460);
FORCEPROP 0 LASTPIN (-5500 3400) $PN BH2
J 2
(-5510 3410);
DISPLAY 0.489362 (-5510 3410);
PAINT MONO (-5510 3410);
FORCEPROP 0 LASTPIN (-5500 3350) $PN BJ2
J 2
(-5510 3360);
DISPLAY 0.489362 (-5510 3360);
PAINT MONO (-5510 3360);
FORCEPROP 0 LASTPIN (-5500 3300) $PN BJ3
J 2
(-5510 3310);
DISPLAY 0.489362 (-5510 3310);
PAINT MONO (-5510 3310);
FORCEPROP 0 LASTPIN (-5500 3250) $PN BK4
J 2
(-5510 3260);
DISPLAY 0.489362 (-5510 3260);
PAINT MONO (-5510 3260);
FORCEPROP 0 LASTPIN (-5500 3200) $PN BK2
J 2
(-5510 3210);
DISPLAY 0.489362 (-5510 3210);
PAINT MONO (-5510 3210);
FORCEPROP 0 LASTPIN (-3900 2000) $PN BY2
J 0
(-3890 2010);
DISPLAY 0.489362 (-3890 2010);
PAINT MONO (-3890 2010);
FORCEPROP 0 LASTPIN (-3900 1950) $PN CA3
J 0
(-3890 1960);
DISPLAY 0.489362 (-3890 1960);
PAINT MONO (-3890 1960);
FORCEPROP 0 LASTPIN (-3900 1900) $PN CA2
J 0
(-3890 1910);
DISPLAY 0.489362 (-3890 1910);
PAINT MONO (-3890 1910);
FORCEPROP 0 LASTPIN (-3900 1850) $PN CB4
J 0
(-3890 1860);
DISPLAY 0.489362 (-3890 1860);
PAINT MONO (-3890 1860);
FORCEPROP 0 LASTPIN (-3900 1800) $PN BT2
J 0
(-3890 1810);
DISPLAY 0.489362 (-3890 1810);
PAINT MONO (-3890 1810);
FORCEPROP 0 LASTPIN (-3900 1750) $PN BU3
J 0
(-3890 1760);
DISPLAY 0.489362 (-3890 1760);
PAINT MONO (-3890 1760);
FORCEPROP 0 LASTPIN (-3900 1700) $PN BU2
J 0
(-3890 1710);
DISPLAY 0.489362 (-3890 1710);
PAINT MONO (-3890 1710);
FORCEPROP 0 LASTPIN (-3900 1650) $PN BV4
J 0
(-3890 1660);
DISPLAY 0.489362 (-3890 1660);
PAINT MONO (-3890 1660);
FORCEPROP 0 LASTPIN (-3900 4250) $PN CB2
J 0
(-3890 4260);
DISPLAY 0.489362 (-3890 4260);
PAINT MONO (-3890 4260);
FORCEPROP 0 LASTPIN (-3900 4200) $PN CC3
J 0
(-3890 4210);
DISPLAY 0.489362 (-3890 4210);
PAINT MONO (-3890 4210);
FORCEPROP 0 LASTPIN (-3900 4150) $PN CC2
J 0
(-3890 4160);
DISPLAY 0.489362 (-3890 4160);
PAINT MONO (-3890 4160);
FORCEPROP 0 LASTPIN (-3900 4100) $PN CD4
J 0
(-3890 4110);
DISPLAY 0.489362 (-3890 4110);
PAINT MONO (-3890 4110);
FORCEPROP 0 LASTPIN (-3900 4050) $PN CF2
J 0
(-3890 4060);
DISPLAY 0.489362 (-3890 4060);
PAINT MONO (-3890 4060);
FORCEPROP 0 LASTPIN (-3900 4000) $PN CG3
J 0
(-3890 4010);
DISPLAY 0.489362 (-3890 4010);
PAINT MONO (-3890 4010);
FORCEPROP 0 LASTPIN (-3900 3950) $PN CG2
J 0
(-3890 3960);
DISPLAY 0.489362 (-3890 3960);
PAINT MONO (-3890 3960);
FORCEPROP 0 LASTPIN (-3900 3900) $PN CH4
J 0
(-3890 3910);
DISPLAY 0.489362 (-3890 3910);
PAINT MONO (-3890 3910);
FORCEPROP 0 LASTPIN (-3900 3800) $PN CH2
J 0
(-3890 3810);
DISPLAY 0.489362 (-3890 3810);
PAINT MONO (-3890 3810);
FORCEPROP 0 LASTPIN (-3900 3750) $PN CJ3
J 0
(-3890 3760);
DISPLAY 0.489362 (-3890 3760);
PAINT MONO (-3890 3760);
FORCEPROP 0 LASTPIN (-3900 3700) $PN CJ2
J 0
(-3890 3710);
DISPLAY 0.489362 (-3890 3710);
PAINT MONO (-3890 3710);
FORCEPROP 0 LASTPIN (-3900 3650) $PN CK4
J 0
(-3890 3660);
DISPLAY 0.489362 (-3890 3660);
PAINT MONO (-3890 3660);
FORCEPROP 0 LASTPIN (-3900 3600) $PN CM2
J 0
(-3890 3610);
DISPLAY 0.489362 (-3890 3610);
PAINT MONO (-3890 3610);
FORCEPROP 0 LASTPIN (-3900 3550) $PN CN3
J 0
(-3890 3560);
DISPLAY 0.489362 (-3890 3560);
PAINT MONO (-3890 3560);
FORCEPROP 0 LASTPIN (-3900 3500) $PN CN2
J 0
(-3890 3510);
DISPLAY 0.489362 (-3890 3510);
PAINT MONO (-3890 3510);
FORCEPROP 0 LASTPIN (-3900 3450) $PN CP4
J 0
(-3890 3460);
DISPLAY 0.489362 (-3890 3460);
PAINT MONO (-3890 3460);
FORCEPROP 0 LASTPIN (-3900 3350) $PN CP2
J 0
(-3890 3360);
DISPLAY 0.489362 (-3890 3360);
PAINT MONO (-3890 3360);
FORCEPROP 0 LASTPIN (-3900 3300) $PN CR3
J 0
(-3890 3310);
DISPLAY 0.489362 (-3890 3310);
PAINT MONO (-3890 3310);
FORCEPROP 0 LASTPIN (-3900 3250) $PN CR2
J 0
(-3890 3260);
DISPLAY 0.489362 (-3890 3260);
PAINT MONO (-3890 3260);
FORCEPROP 0 LASTPIN (-3900 3200) $PN CT4
J 0
(-3890 3210);
DISPLAY 0.489362 (-3890 3210);
PAINT MONO (-3890 3210);
FORCEPROP 0 LASTPIN (-3900 3150) $PN CV2
J 0
(-3890 3160);
DISPLAY 0.489362 (-3890 3160);
PAINT MONO (-3890 3160);
FORCEPROP 0 LASTPIN (-3900 3100) $PN CW3
J 0
(-3890 3110);
DISPLAY 0.489362 (-3890 3110);
PAINT MONO (-3890 3110);
FORCEPROP 0 LASTPIN (-3900 3050) $PN CW2
J 0
(-3890 3060);
DISPLAY 0.489362 (-3890 3060);
PAINT MONO (-3890 3060);
FORCEPROP 0 LASTPIN (-3900 3000) $PN CY4
J 0
(-3890 3010);
DISPLAY 0.489362 (-3890 3010);
PAINT MONO (-3890 3010);
FORCEPROP 0 LASTPIN (-3900 2900) $PN CY2
J 0
(-3890 2910);
DISPLAY 0.489362 (-3890 2910);
PAINT MONO (-3890 2910);
FORCEPROP 0 LASTPIN (-3900 2850) $PN DA3
J 0
(-3890 2860);
DISPLAY 0.489362 (-3890 2860);
PAINT MONO (-3890 2860);
FORCEPROP 0 LASTPIN (-3900 2800) $PN DA2
J 0
(-3890 2810);
DISPLAY 0.489362 (-3890 2810);
PAINT MONO (-3890 2810);
FORCEPROP 0 LASTPIN (-3900 2750) $PN DB4
J 0
(-3890 2760);
DISPLAY 0.489362 (-3890 2760);
PAINT MONO (-3890 2760);
FORCEPROP 0 LASTPIN (-3900 2700) $PN DD2
J 0
(-3890 2710);
DISPLAY 0.489362 (-3890 2710);
PAINT MONO (-3890 2710);
FORCEPROP 0 LASTPIN (-3900 2650) $PN DE3
J 0
(-3890 2660);
DISPLAY 0.489362 (-3890 2660);
PAINT MONO (-3890 2660);
FORCEPROP 0 LASTPIN (-3900 2600) $PN DE2
J 0
(-3890 2610);
DISPLAY 0.489362 (-3890 2610);
PAINT MONO (-3890 2610);
FORCEPROP 0 LASTPIN (-3900 2550) $PN DF2
J 0
(-3890 2560);
DISPLAY 0.489362 (-3890 2560);
PAINT MONO (-3890 2560);
FORCEPROP 0 LASTPIN (-5500 5000) $PN CD2
J 2
(-5510 5010);
DISPLAY 0.489362 (-5510 5010);
PAINT MONO (-5510 5010);
FORCEPROP 0 LASTPIN (-5500 4900) $PN CK2
J 2
(-5510 4910);
DISPLAY 0.489362 (-5510 4910);
PAINT MONO (-5510 4910);
FORCEPROP 0 LASTPIN (-5500 4800) $PN CT2
J 2
(-5510 4810);
DISPLAY 0.489362 (-5510 4810);
PAINT MONO (-5510 4810);
FORCEPROP 0 LASTPIN (-5500 4700) $PN DB2
J 2
(-5510 4710);
DISPLAY 0.489362 (-5510 4710);
PAINT MONO (-5510 4710);
FORCEPROP 0 LASTPIN (-5500 4600) $PN BY4
J 2
(-5510 4610);
DISPLAY 0.489362 (-5510 4610);
PAINT MONO (-5510 4610);
FORCEPROP 0 LASTPIN (-5500 4500) $PN CF4
J 2
(-5510 4510);
DISPLAY 0.489362 (-5510 4510);
PAINT MONO (-5510 4510);
FORCEPROP 0 LASTPIN (-5500 4400) $PN CM4
J 2
(-5510 4410);
DISPLAY 0.489362 (-5510 4410);
PAINT MONO (-5510 4410);
FORCEPROP 0 LASTPIN (-5500 4300) $PN CV4
J 2
(-5510 4310);
DISPLAY 0.489362 (-5510 4310);
PAINT MONO (-5510 4310);
FORCEPROP 0 LASTPIN (-5500 4200) $PN DD4
J 2
(-5510 4210);
DISPLAY 0.489362 (-5510 4210);
PAINT MONO (-5510 4210);
FORCEPROP 0 LASTPIN (-5500 4100) $PN BV2
J 2
(-5510 4110);
DISPLAY 0.489362 (-5510 4110);
PAINT MONO (-5510 4110);
FORCEPROP 0 LASTPIN (-5500 4950) $PN CE2
J 2
(-5510 4960);
DISPLAY 0.489362 (-5510 4960);
PAINT MONO (-5510 4960);
FORCEPROP 0 LASTPIN (-5500 4850) $PN CL2
J 2
(-5510 4860);
DISPLAY 0.489362 (-5510 4860);
PAINT MONO (-5510 4860);
FORCEPROP 0 LASTPIN (-5500 4750) $PN CU2
J 2
(-5510 4760);
DISPLAY 0.489362 (-5510 4760);
PAINT MONO (-5510 4760);
FORCEPROP 0 LASTPIN (-5500 4650) $PN DC2
J 2
(-5510 4660);
DISPLAY 0.489362 (-5510 4660);
PAINT MONO (-5510 4660);
FORCEPROP 0 LASTPIN (-5500 4550) $PN BW3
J 2
(-5510 4560);
DISPLAY 0.489362 (-5510 4560);
PAINT MONO (-5510 4560);
FORCEPROP 0 LASTPIN (-5500 4450) $PN CE3
J 2
(-5510 4460);
DISPLAY 0.489362 (-5510 4460);
PAINT MONO (-5510 4460);
FORCEPROP 0 LASTPIN (-5500 4350) $PN CL3
J 2
(-5510 4360);
DISPLAY 0.489362 (-5510 4360);
PAINT MONO (-5510 4360);
FORCEPROP 0 LASTPIN (-5500 4250) $PN CU3
J 2
(-5510 4260);
DISPLAY 0.489362 (-5510 4260);
PAINT MONO (-5510 4260);
FORCEPROP 0 LASTPIN (-5500 4150) $PN DC3
J 2
(-5510 4160);
DISPLAY 0.489362 (-5510 4160);
PAINT MONO (-5510 4160);
FORCEPROP 0 LASTPIN (-5500 4050) $PN BW2
J 2
(-5510 4060);
DISPLAY 0.489362 (-5510 4060);
PAINT MONO (-5510 4060);
FORCEPROP 0 LASTPIN (-5500 2300) $PN BL3
J 2
(-5510 2310);
DISPLAY 0.489362 (-5510 2310);
PAINT MONO (-5510 2310);
FORCEPROP 0 LASTPIN (-5500 1250) $PN BF4
J 2
(-5510 1260);
DISPLAY 0.489362 (-5510 1260);
PAINT MONO (-5510 1260);
FORCEPROP 2 LAST PART_TYPE SMLF
J 0
(-5325 6455);
DISPLAY 1.021277 (-5325 6455);
FORCEPROP 1 LAST MATERIAL IO
J 0
(-5345 6232);
DISPLAY 0.489362 (-5345 6232);
PAINT SKYBLUE (-5345 6232);
FORCEPROP 2 LAST VALUE SOCKET6096_13568-001
J 0
(-5325 6355);
DISPLAY 0.489362 (-5325 6355);
PAINT SKYBLUE (-5325 6355);
FORCEPROP 1 LAST PART_NUMBER DGA^6000030
J 0
(-5345 6359);
DISPLAY 0.489362 (-5345 6359);
PAINT SKYBLUE (-5345 6359);
FORCEPROP 2 LAST CDS_LIB pure_quanta
J 0
(-4700 3675);
DISPLAY INVISIBLE (-4700 3675);
FORCEPROP 1 LAST CDS_LMAN_SYM_OUTLINE -650,2525,650,-2525
J 0
(-4700 3675);
DISPLAY 0.468085 (-4700 3675);
PAINT GREEN (-4700 3675);
DISPLAY INVISIBLE (-4700 3675);
FORCEPROP 1 LAST NEEDS_NO_SIZE TRUE
J 0
(-4700 3675);
DISPLAY 0.723404 (-4700 3675);
PAINT GREEN (-4700 3675);
DISPLAY INVISIBLE (-4700 3675);
FORCEPROP 1 LAST PATH I167
J 0
(-4700 3675);
DISPLAY 0.723404 (-4700 3675);
PAINT GREEN (-4700 3675);
DISPLAY INVISIBLE (-4700 3675);
FORCEADD OFFPAGE..3
(-2700 6075);
FORCEPROP 2 LAST $XR0 91 
J 0
(-2486 6075);
DISPLAY 0.638298 (-2486 6075);
PAINT MONO (-2486 6075);
FORCEPROP 2 LAST PATH I168
J 0
(-2475 6125);
DISPLAY 1.021277 (-2475 6125);
DISPLAY INVISIBLE (-2475 6125);
FORCEPROP 1 LAST COMMENT_BODY TRUE
J 0
(-2750 5975);
DISPLAY 0.872340 (-2750 5975);
PAINT GREEN (-2750 5975);
DISPLAY INVISIBLE (-2750 5975);
FORCEPROP 1 LAST OFFPAGE TRUE
J 0
(-2375 5950);
DISPLAY 0.872340 (-2375 5950);
PAINT GREEN (-2375 5950);
DISPLAY INVISIBLE (-2375 5950);
FORCEPROP 2 LAST CDS_LIB mstr_standard
J 0
(-2700 6075);
DISPLAY 0.723404 (-2700 6075);
PAINT MONO (-2700 6075);
DISPLAY INVISIBLE (-2700 6075);
FORCEADD OFFPAGE..3
(-2700 4275);
FORCEPROP 2 LAST $XR0 91 
J 0
(-2486 4275);
DISPLAY 0.638298 (-2486 4275);
PAINT MONO (-2486 4275);
FORCEPROP 2 LAST PATH I169
J 0
(-2475 4325);
DISPLAY 1.021277 (-2475 4325);
DISPLAY INVISIBLE (-2475 4325);
FORCEPROP 1 LAST COMMENT_BODY TRUE
J 0
(-2750 4175);
DISPLAY 0.872340 (-2750 4175);
PAINT GREEN (-2750 4175);
DISPLAY INVISIBLE (-2750 4175);
FORCEPROP 1 LAST OFFPAGE TRUE
J 0
(-2375 4150);
DISPLAY 0.872340 (-2375 4150);
PAINT GREEN (-2375 4150);
DISPLAY INVISIBLE (-2375 4150);
FORCEPROP 2 LAST CDS_LIB mstr_standard
J 0
(-2700 4275);
DISPLAY 0.723404 (-2700 4275);
PAINT MONO (-2700 4275);
DISPLAY INVISIBLE (-2700 4275);
FORCEADD TAP..1
(-3425 6050);
FORCEPROP 3 LASTPIN (-3475 6050) SIG_NAME M_G_CPU0_SA_DQ<0>
J 0
(-3465 6060);
DISPLAY 0.659574 (-3465 6060);
PAINT MONO (-3465 6060);
DISPLAY INVISIBLE (-3465 6060);
FORCEPROP 1 LASTPIN (-3475 6050) BN 0
J 0
(-3487 6058);
DISPLAY 0.489362 (-3487 6058);
PAINT GREEN (-3487 6058);
FORCEPROP 2 LAST CDS_LIB mstr_standard
J 0
(-3425 6050);
DISPLAY 0.723404 (-3425 6050);
PAINT MONO (-3425 6050);
DISPLAY INVISIBLE (-3425 6050);
FORCEPROP 1 LAST BODY_TYPE PLUMBING
J 0
(-3425 6100);
DISPLAY 0.872340 (-3425 6100);
PAINT GREEN (-3425 6100);
DISPLAY INVISIBLE (-3425 6100);
FORCEPROP 1 LAST HDL_TAP TRUE
J 0
(-3100 5925);
DISPLAY 0.872340 (-3100 5925);
DISPLAY INVISIBLE (-3100 5925);
FORCEPROP 1 LAST PATH I170
J 0
(-3427 6050);
DISPLAY 0.872340 (-3427 6050);
PAINT GREEN (-3427 6050);
DISPLAY INVISIBLE (-3427 6050);
FORCEADD TAP..1
(-3425 6000);
FORCEPROP 3 LASTPIN (-3475 6000) SIG_NAME M_G_CPU0_SA_DQ<1>
J 0
(-3465 6010);
DISPLAY 0.659574 (-3465 6010);
PAINT MONO (-3465 6010);
DISPLAY INVISIBLE (-3465 6010);
FORCEPROP 1 LASTPIN (-3475 6000) BN 1
J 0
(-3487 6008);
DISPLAY 0.489362 (-3487 6008);
PAINT GREEN (-3487 6008);
FORCEPROP 2 LAST CDS_LIB mstr_standard
J 0
(-3425 6000);
DISPLAY 0.723404 (-3425 6000);
PAINT MONO (-3425 6000);
DISPLAY INVISIBLE (-3425 6000);
FORCEPROP 1 LAST BODY_TYPE PLUMBING
J 0
(-3425 6050);
DISPLAY 0.872340 (-3425 6050);
PAINT GREEN (-3425 6050);
DISPLAY INVISIBLE (-3425 6050);
FORCEPROP 1 LAST HDL_TAP TRUE
J 0
(-3100 5875);
DISPLAY 0.872340 (-3100 5875);
DISPLAY INVISIBLE (-3100 5875);
FORCEPROP 1 LAST PATH I171
J 0
(-3427 6000);
DISPLAY 0.872340 (-3427 6000);
PAINT GREEN (-3427 6000);
DISPLAY INVISIBLE (-3427 6000);
FORCEADD TAP..1
(-3425 5950);
FORCEPROP 3 LASTPIN (-3475 5950) SIG_NAME M_G_CPU0_SA_DQ<2>
J 0
(-3465 5960);
DISPLAY 0.659574 (-3465 5960);
PAINT MONO (-3465 5960);
DISPLAY INVISIBLE (-3465 5960);
FORCEPROP 1 LASTPIN (-3475 5950) BN 2
J 0
(-3487 5958);
DISPLAY 0.489362 (-3487 5958);
PAINT GREEN (-3487 5958);
FORCEPROP 2 LAST CDS_LIB mstr_standard
J 0
(-3425 5950);
DISPLAY 0.723404 (-3425 5950);
PAINT MONO (-3425 5950);
DISPLAY INVISIBLE (-3425 5950);
FORCEPROP 1 LAST BODY_TYPE PLUMBING
J 0
(-3425 6000);
DISPLAY 0.872340 (-3425 6000);
PAINT GREEN (-3425 6000);
DISPLAY INVISIBLE (-3425 6000);
FORCEPROP 1 LAST HDL_TAP TRUE
J 0
(-3100 5825);
DISPLAY 0.872340 (-3100 5825);
DISPLAY INVISIBLE (-3100 5825);
FORCEPROP 1 LAST PATH I172
J 0
(-3427 5950);
DISPLAY 0.872340 (-3427 5950);
PAINT GREEN (-3427 5950);
DISPLAY INVISIBLE (-3427 5950);
FORCEADD TAP..1
(-3425 5900);
FORCEPROP 3 LASTPIN (-3475 5900) SIG_NAME M_G_CPU0_SA_DQ<3>
J 0
(-3465 5910);
DISPLAY 0.659574 (-3465 5910);
PAINT MONO (-3465 5910);
DISPLAY INVISIBLE (-3465 5910);
FORCEPROP 1 LASTPIN (-3475 5900) BN 3
J 0
(-3487 5908);
DISPLAY 0.489362 (-3487 5908);
PAINT GREEN (-3487 5908);
FORCEPROP 2 LAST CDS_LIB mstr_standard
J 0
(-3425 5900);
DISPLAY 0.723404 (-3425 5900);
PAINT MONO (-3425 5900);
DISPLAY INVISIBLE (-3425 5900);
FORCEPROP 1 LAST BODY_TYPE PLUMBING
J 0
(-3425 5950);
DISPLAY 0.872340 (-3425 5950);
PAINT GREEN (-3425 5950);
DISPLAY INVISIBLE (-3425 5950);
FORCEPROP 1 LAST HDL_TAP TRUE
J 0
(-3100 5775);
DISPLAY 0.872340 (-3100 5775);
DISPLAY INVISIBLE (-3100 5775);
FORCEPROP 1 LAST PATH I173
J 0
(-3427 5900);
DISPLAY 0.872340 (-3427 5900);
PAINT GREEN (-3427 5900);
DISPLAY INVISIBLE (-3427 5900);
FORCEADD TAP..1
(-3425 5850);
FORCEPROP 3 LASTPIN (-3475 5850) SIG_NAME M_G_CPU0_SA_DQ<4>
J 0
(-3465 5860);
DISPLAY 0.659574 (-3465 5860);
PAINT MONO (-3465 5860);
DISPLAY INVISIBLE (-3465 5860);
FORCEPROP 1 LASTPIN (-3475 5850) BN 4
J 0
(-3487 5858);
DISPLAY 0.489362 (-3487 5858);
PAINT GREEN (-3487 5858);
FORCEPROP 2 LAST CDS_LIB mstr_standard
J 0
(-3425 5850);
DISPLAY 0.723404 (-3425 5850);
PAINT MONO (-3425 5850);
DISPLAY INVISIBLE (-3425 5850);
FORCEPROP 1 LAST BODY_TYPE PLUMBING
J 0
(-3425 5900);
DISPLAY 0.872340 (-3425 5900);
PAINT GREEN (-3425 5900);
DISPLAY INVISIBLE (-3425 5900);
FORCEPROP 1 LAST HDL_TAP TRUE
J 0
(-3100 5725);
DISPLAY 0.872340 (-3100 5725);
DISPLAY INVISIBLE (-3100 5725);
FORCEPROP 1 LAST PATH I174
J 0
(-3427 5850);
DISPLAY 0.872340 (-3427 5850);
PAINT GREEN (-3427 5850);
DISPLAY INVISIBLE (-3427 5850);
FORCEADD TAP..1
(-3425 5800);
FORCEPROP 3 LASTPIN (-3475 5800) SIG_NAME M_G_CPU0_SA_DQ<5>
J 0
(-3465 5810);
DISPLAY 0.659574 (-3465 5810);
PAINT MONO (-3465 5810);
DISPLAY INVISIBLE (-3465 5810);
FORCEPROP 1 LASTPIN (-3475 5800) BN 5
J 0
(-3487 5808);
DISPLAY 0.489362 (-3487 5808);
PAINT GREEN (-3487 5808);
FORCEPROP 2 LAST CDS_LIB mstr_standard
J 0
(-3425 5800);
DISPLAY 0.723404 (-3425 5800);
PAINT MONO (-3425 5800);
DISPLAY INVISIBLE (-3425 5800);
FORCEPROP 1 LAST BODY_TYPE PLUMBING
J 0
(-3425 5850);
DISPLAY 0.872340 (-3425 5850);
PAINT GREEN (-3425 5850);
DISPLAY INVISIBLE (-3425 5850);
FORCEPROP 1 LAST HDL_TAP TRUE
J 0
(-3100 5675);
DISPLAY 0.872340 (-3100 5675);
DISPLAY INVISIBLE (-3100 5675);
FORCEPROP 1 LAST PATH I175
J 0
(-3427 5800);
DISPLAY 0.872340 (-3427 5800);
PAINT GREEN (-3427 5800);
DISPLAY INVISIBLE (-3427 5800);
FORCEADD TAP..1
(-3425 5700);
FORCEPROP 3 LASTPIN (-3475 5700) SIG_NAME M_G_CPU0_SA_DQ<7>
J 0
(-3465 5710);
DISPLAY 0.659574 (-3465 5710);
PAINT MONO (-3465 5710);
DISPLAY INVISIBLE (-3465 5710);
FORCEPROP 1 LASTPIN (-3475 5700) BN 7
J 0
(-3487 5708);
DISPLAY 0.489362 (-3487 5708);
PAINT GREEN (-3487 5708);
FORCEPROP 2 LAST CDS_LIB mstr_standard
J 0
(-3425 5700);
DISPLAY 0.723404 (-3425 5700);
PAINT MONO (-3425 5700);
DISPLAY INVISIBLE (-3425 5700);
FORCEPROP 1 LAST BODY_TYPE PLUMBING
J 0
(-3425 5750);
DISPLAY 0.872340 (-3425 5750);
PAINT GREEN (-3425 5750);
DISPLAY INVISIBLE (-3425 5750);
FORCEPROP 1 LAST HDL_TAP TRUE
J 0
(-3100 5575);
DISPLAY 0.872340 (-3100 5575);
DISPLAY INVISIBLE (-3100 5575);
FORCEPROP 1 LAST PATH I176
J 0
(-3427 5700);
DISPLAY 0.872340 (-3427 5700);
PAINT GREEN (-3427 5700);
DISPLAY INVISIBLE (-3427 5700);
FORCEADD TAP..1
(-3425 5750);
FORCEPROP 3 LASTPIN (-3475 5750) SIG_NAME M_G_CPU0_SA_DQ<6>
J 0
(-3465 5760);
DISPLAY 0.659574 (-3465 5760);
PAINT MONO (-3465 5760);
DISPLAY INVISIBLE (-3465 5760);
FORCEPROP 1 LASTPIN (-3475 5750) BN 6
J 0
(-3487 5758);
DISPLAY 0.489362 (-3487 5758);
PAINT GREEN (-3487 5758);
FORCEPROP 2 LAST CDS_LIB mstr_standard
J 0
(-3425 5750);
DISPLAY 0.723404 (-3425 5750);
PAINT MONO (-3425 5750);
DISPLAY INVISIBLE (-3425 5750);
FORCEPROP 1 LAST BODY_TYPE PLUMBING
J 0
(-3425 5800);
DISPLAY 0.872340 (-3425 5800);
PAINT GREEN (-3425 5800);
DISPLAY INVISIBLE (-3425 5800);
FORCEPROP 1 LAST HDL_TAP TRUE
J 0
(-3100 5625);
DISPLAY 0.872340 (-3100 5625);
DISPLAY INVISIBLE (-3100 5625);
FORCEPROP 1 LAST PATH I177
J 0
(-3427 5750);
DISPLAY 0.872340 (-3427 5750);
PAINT GREEN (-3427 5750);
DISPLAY INVISIBLE (-3427 5750);
FORCEADD TAP..1
(-3425 5600);
FORCEPROP 3 LASTPIN (-3475 5600) SIG_NAME M_G_CPU0_SA_DQ<8>
J 0
(-3465 5610);
DISPLAY 0.659574 (-3465 5610);
PAINT MONO (-3465 5610);
DISPLAY INVISIBLE (-3465 5610);
FORCEPROP 1 LASTPIN (-3475 5600) BN 8
J 0
(-3487 5608);
DISPLAY 0.489362 (-3487 5608);
PAINT GREEN (-3487 5608);
FORCEPROP 2 LAST CDS_LIB mstr_standard
J 0
(-3425 5600);
DISPLAY 0.723404 (-3425 5600);
PAINT MONO (-3425 5600);
DISPLAY INVISIBLE (-3425 5600);
FORCEPROP 1 LAST BODY_TYPE PLUMBING
J 0
(-3425 5650);
DISPLAY 0.872340 (-3425 5650);
PAINT GREEN (-3425 5650);
DISPLAY INVISIBLE (-3425 5650);
FORCEPROP 1 LAST HDL_TAP TRUE
J 0
(-3100 5475);
DISPLAY 0.872340 (-3100 5475);
DISPLAY INVISIBLE (-3100 5475);
FORCEPROP 1 LAST PATH I178
J 0
(-3427 5600);
DISPLAY 0.872340 (-3427 5600);
PAINT GREEN (-3427 5600);
DISPLAY INVISIBLE (-3427 5600);
FORCEADD TAP..1
(-3425 5550);
FORCEPROP 3 LASTPIN (-3475 5550) SIG_NAME M_G_CPU0_SA_DQ<9>
J 0
(-3465 5560);
DISPLAY 0.659574 (-3465 5560);
PAINT MONO (-3465 5560);
DISPLAY INVISIBLE (-3465 5560);
FORCEPROP 1 LASTPIN (-3475 5550) BN 9
J 0
(-3487 5558);
DISPLAY 0.489362 (-3487 5558);
PAINT GREEN (-3487 5558);
FORCEPROP 2 LAST CDS_LIB mstr_standard
J 0
(-3425 5550);
DISPLAY 0.723404 (-3425 5550);
PAINT MONO (-3425 5550);
DISPLAY INVISIBLE (-3425 5550);
FORCEPROP 1 LAST BODY_TYPE PLUMBING
J 0
(-3425 5600);
DISPLAY 0.872340 (-3425 5600);
PAINT GREEN (-3425 5600);
DISPLAY INVISIBLE (-3425 5600);
FORCEPROP 1 LAST HDL_TAP TRUE
J 0
(-3100 5425);
DISPLAY 0.872340 (-3100 5425);
DISPLAY INVISIBLE (-3100 5425);
FORCEPROP 1 LAST PATH I179
J 0
(-3427 5550);
DISPLAY 0.872340 (-3427 5550);
PAINT GREEN (-3427 5550);
DISPLAY INVISIBLE (-3427 5550);
FORCEADD TAP..1
(-3425 5450);
FORCEPROP 3 LASTPIN (-3475 5450) SIG_NAME M_G_CPU0_SA_DQ<11>
J 0
(-3465 5460);
DISPLAY 0.659574 (-3465 5460);
PAINT MONO (-3465 5460);
DISPLAY INVISIBLE (-3465 5460);
FORCEPROP 1 LASTPIN (-3475 5450) BN 11
J 0
(-3487 5458);
DISPLAY 0.489362 (-3487 5458);
PAINT GREEN (-3487 5458);
FORCEPROP 2 LAST CDS_LIB mstr_standard
J 0
(-3425 5450);
DISPLAY 0.723404 (-3425 5450);
PAINT MONO (-3425 5450);
DISPLAY INVISIBLE (-3425 5450);
FORCEPROP 1 LAST BODY_TYPE PLUMBING
J 0
(-3425 5500);
DISPLAY 0.872340 (-3425 5500);
PAINT GREEN (-3425 5500);
DISPLAY INVISIBLE (-3425 5500);
FORCEPROP 1 LAST HDL_TAP TRUE
J 0
(-3100 5325);
DISPLAY 0.872340 (-3100 5325);
DISPLAY INVISIBLE (-3100 5325);
FORCEPROP 1 LAST PATH I180
J 0
(-3427 5450);
DISPLAY 0.872340 (-3427 5450);
PAINT GREEN (-3427 5450);
DISPLAY INVISIBLE (-3427 5450);
FORCEADD TAP..1
(-3425 5500);
FORCEPROP 3 LASTPIN (-3475 5500) SIG_NAME M_G_CPU0_SA_DQ<10>
J 0
(-3465 5510);
DISPLAY 0.659574 (-3465 5510);
PAINT MONO (-3465 5510);
DISPLAY INVISIBLE (-3465 5510);
FORCEPROP 1 LASTPIN (-3475 5500) BN 10
J 0
(-3487 5508);
DISPLAY 0.489362 (-3487 5508);
PAINT GREEN (-3487 5508);
FORCEPROP 2 LAST CDS_LIB mstr_standard
J 0
(-3425 5500);
DISPLAY 0.723404 (-3425 5500);
PAINT MONO (-3425 5500);
DISPLAY INVISIBLE (-3425 5500);
FORCEPROP 1 LAST BODY_TYPE PLUMBING
J 0
(-3425 5550);
DISPLAY 0.872340 (-3425 5550);
PAINT GREEN (-3425 5550);
DISPLAY INVISIBLE (-3425 5550);
FORCEPROP 1 LAST HDL_TAP TRUE
J 0
(-3100 5375);
DISPLAY 0.872340 (-3100 5375);
DISPLAY INVISIBLE (-3100 5375);
FORCEPROP 1 LAST PATH I181
J 0
(-3427 5500);
DISPLAY 0.872340 (-3427 5500);
PAINT GREEN (-3427 5500);
DISPLAY INVISIBLE (-3427 5500);
FORCEADD TAP..1
(-3425 5400);
FORCEPROP 3 LASTPIN (-3475 5400) SIG_NAME M_G_CPU0_SA_DQ<12>
J 0
(-3465 5410);
DISPLAY 0.659574 (-3465 5410);
PAINT MONO (-3465 5410);
DISPLAY INVISIBLE (-3465 5410);
FORCEPROP 1 LASTPIN (-3475 5400) BN 12
J 0
(-3487 5408);
DISPLAY 0.489362 (-3487 5408);
PAINT GREEN (-3487 5408);
FORCEPROP 2 LAST CDS_LIB mstr_standard
J 0
(-3425 5400);
DISPLAY 0.723404 (-3425 5400);
PAINT MONO (-3425 5400);
DISPLAY INVISIBLE (-3425 5400);
FORCEPROP 1 LAST BODY_TYPE PLUMBING
J 0
(-3425 5450);
DISPLAY 0.872340 (-3425 5450);
PAINT GREEN (-3425 5450);
DISPLAY INVISIBLE (-3425 5450);
FORCEPROP 1 LAST HDL_TAP TRUE
J 0
(-3100 5275);
DISPLAY 0.872340 (-3100 5275);
DISPLAY INVISIBLE (-3100 5275);
FORCEPROP 1 LAST PATH I182
J 0
(-3427 5400);
DISPLAY 0.872340 (-3427 5400);
PAINT GREEN (-3427 5400);
DISPLAY INVISIBLE (-3427 5400);
FORCEADD TAP..1
(-3425 5350);
FORCEPROP 3 LASTPIN (-3475 5350) SIG_NAME M_G_CPU0_SA_DQ<13>
J 0
(-3465 5360);
DISPLAY 0.659574 (-3465 5360);
PAINT MONO (-3465 5360);
DISPLAY INVISIBLE (-3465 5360);
FORCEPROP 1 LASTPIN (-3475 5350) BN 13
J 0
(-3487 5358);
DISPLAY 0.489362 (-3487 5358);
PAINT GREEN (-3487 5358);
FORCEPROP 2 LAST CDS_LIB mstr_standard
J 0
(-3425 5350);
DISPLAY 0.723404 (-3425 5350);
PAINT MONO (-3425 5350);
DISPLAY INVISIBLE (-3425 5350);
FORCEPROP 1 LAST BODY_TYPE PLUMBING
J 0
(-3425 5400);
DISPLAY 0.872340 (-3425 5400);
PAINT GREEN (-3425 5400);
DISPLAY INVISIBLE (-3425 5400);
FORCEPROP 1 LAST HDL_TAP TRUE
J 0
(-3100 5225);
DISPLAY 0.872340 (-3100 5225);
DISPLAY INVISIBLE (-3100 5225);
FORCEPROP 1 LAST PATH I183
J 0
(-3427 5350);
DISPLAY 0.872340 (-3427 5350);
PAINT GREEN (-3427 5350);
DISPLAY INVISIBLE (-3427 5350);
FORCEADD TAP..1
(-3425 5250);
FORCEPROP 3 LASTPIN (-3475 5250) SIG_NAME M_G_CPU0_SA_DQ<15>
J 0
(-3465 5260);
DISPLAY 0.659574 (-3465 5260);
PAINT MONO (-3465 5260);
DISPLAY INVISIBLE (-3465 5260);
FORCEPROP 1 LASTPIN (-3475 5250) BN 15
J 0
(-3487 5258);
DISPLAY 0.489362 (-3487 5258);
PAINT GREEN (-3487 5258);
FORCEPROP 2 LAST CDS_LIB mstr_standard
J 0
(-3425 5250);
DISPLAY 0.723404 (-3425 5250);
PAINT MONO (-3425 5250);
DISPLAY INVISIBLE (-3425 5250);
FORCEPROP 1 LAST BODY_TYPE PLUMBING
J 0
(-3425 5300);
DISPLAY 0.872340 (-3425 5300);
PAINT GREEN (-3425 5300);
DISPLAY INVISIBLE (-3425 5300);
FORCEPROP 1 LAST HDL_TAP TRUE
J 0
(-3100 5125);
DISPLAY 0.872340 (-3100 5125);
DISPLAY INVISIBLE (-3100 5125);
FORCEPROP 1 LAST PATH I184
J 0
(-3427 5250);
DISPLAY 0.872340 (-3427 5250);
PAINT GREEN (-3427 5250);
DISPLAY INVISIBLE (-3427 5250);
FORCEADD TAP..1
(-3425 5300);
FORCEPROP 3 LASTPIN (-3475 5300) SIG_NAME M_G_CPU0_SA_DQ<14>
J 0
(-3465 5310);
DISPLAY 0.659574 (-3465 5310);
PAINT MONO (-3465 5310);
DISPLAY INVISIBLE (-3465 5310);
FORCEPROP 1 LASTPIN (-3475 5300) BN 14
J 0
(-3487 5308);
DISPLAY 0.489362 (-3487 5308);
PAINT GREEN (-3487 5308);
FORCEPROP 2 LAST CDS_LIB mstr_standard
J 0
(-3425 5300);
DISPLAY 0.723404 (-3425 5300);
PAINT MONO (-3425 5300);
DISPLAY INVISIBLE (-3425 5300);
FORCEPROP 1 LAST BODY_TYPE PLUMBING
J 0
(-3425 5350);
DISPLAY 0.872340 (-3425 5350);
PAINT GREEN (-3425 5350);
DISPLAY INVISIBLE (-3425 5350);
FORCEPROP 1 LAST HDL_TAP TRUE
J 0
(-3100 5175);
DISPLAY 0.872340 (-3100 5175);
DISPLAY INVISIBLE (-3100 5175);
FORCEPROP 1 LAST PATH I185
J 0
(-3427 5300);
DISPLAY 0.872340 (-3427 5300);
PAINT GREEN (-3427 5300);
DISPLAY INVISIBLE (-3427 5300);
FORCEADD TAP..1
(-3425 5150);
FORCEPROP 3 LASTPIN (-3475 5150) SIG_NAME M_G_CPU0_SA_DQ<16>
J 0
(-3465 5160);
DISPLAY 0.659574 (-3465 5160);
PAINT MONO (-3465 5160);
DISPLAY INVISIBLE (-3465 5160);
FORCEPROP 1 LASTPIN (-3475 5150) BN 16
J 0
(-3487 5158);
DISPLAY 0.489362 (-3487 5158);
PAINT GREEN (-3487 5158);
FORCEPROP 2 LAST CDS_LIB mstr_standard
J 0
(-3425 5150);
DISPLAY 0.723404 (-3425 5150);
PAINT MONO (-3425 5150);
DISPLAY INVISIBLE (-3425 5150);
FORCEPROP 1 LAST BODY_TYPE PLUMBING
J 0
(-3425 5200);
DISPLAY 0.872340 (-3425 5200);
PAINT GREEN (-3425 5200);
DISPLAY INVISIBLE (-3425 5200);
FORCEPROP 1 LAST HDL_TAP TRUE
J 0
(-3100 5025);
DISPLAY 0.872340 (-3100 5025);
DISPLAY INVISIBLE (-3100 5025);
FORCEPROP 1 LAST PATH I186
J 0
(-3427 5150);
DISPLAY 0.872340 (-3427 5150);
PAINT GREEN (-3427 5150);
DISPLAY INVISIBLE (-3427 5150);
FORCEADD TAP..1
(-3425 5100);
FORCEPROP 3 LASTPIN (-3475 5100) SIG_NAME M_G_CPU0_SA_DQ<17>
J 0
(-3465 5110);
DISPLAY 0.659574 (-3465 5110);
PAINT MONO (-3465 5110);
DISPLAY INVISIBLE (-3465 5110);
FORCEPROP 1 LASTPIN (-3475 5100) BN 17
J 0
(-3487 5108);
DISPLAY 0.489362 (-3487 5108);
PAINT GREEN (-3487 5108);
FORCEPROP 2 LAST CDS_LIB mstr_standard
J 0
(-3425 5100);
DISPLAY 0.723404 (-3425 5100);
PAINT MONO (-3425 5100);
DISPLAY INVISIBLE (-3425 5100);
FORCEPROP 1 LAST BODY_TYPE PLUMBING
J 0
(-3425 5150);
DISPLAY 0.872340 (-3425 5150);
PAINT GREEN (-3425 5150);
DISPLAY INVISIBLE (-3425 5150);
FORCEPROP 1 LAST HDL_TAP TRUE
J 0
(-3100 4975);
DISPLAY 0.872340 (-3100 4975);
DISPLAY INVISIBLE (-3100 4975);
FORCEPROP 1 LAST PATH I187
J 0
(-3427 5100);
DISPLAY 0.872340 (-3427 5100);
PAINT GREEN (-3427 5100);
DISPLAY INVISIBLE (-3427 5100);
FORCEADD TAP..1
(-3425 5050);
FORCEPROP 3 LASTPIN (-3475 5050) SIG_NAME M_G_CPU0_SA_DQ<18>
J 0
(-3465 5060);
DISPLAY 0.659574 (-3465 5060);
PAINT MONO (-3465 5060);
DISPLAY INVISIBLE (-3465 5060);
FORCEPROP 1 LASTPIN (-3475 5050) BN 18
J 0
(-3487 5058);
DISPLAY 0.489362 (-3487 5058);
PAINT GREEN (-3487 5058);
FORCEPROP 2 LAST CDS_LIB mstr_standard
J 0
(-3425 5050);
DISPLAY 0.723404 (-3425 5050);
PAINT MONO (-3425 5050);
DISPLAY INVISIBLE (-3425 5050);
FORCEPROP 1 LAST BODY_TYPE PLUMBING
J 0
(-3425 5100);
DISPLAY 0.872340 (-3425 5100);
PAINT GREEN (-3425 5100);
DISPLAY INVISIBLE (-3425 5100);
FORCEPROP 1 LAST HDL_TAP TRUE
J 0
(-3100 4925);
DISPLAY 0.872340 (-3100 4925);
DISPLAY INVISIBLE (-3100 4925);
FORCEPROP 1 LAST PATH I188
J 0
(-3427 5050);
DISPLAY 0.872340 (-3427 5050);
PAINT GREEN (-3427 5050);
DISPLAY INVISIBLE (-3427 5050);
FORCEADD TAP..1
(-3425 5000);
FORCEPROP 3 LASTPIN (-3475 5000) SIG_NAME M_G_CPU0_SA_DQ<19>
J 0
(-3465 5010);
DISPLAY 0.659574 (-3465 5010);
PAINT MONO (-3465 5010);
DISPLAY INVISIBLE (-3465 5010);
FORCEPROP 1 LASTPIN (-3475 5000) BN 19
J 0
(-3487 5008);
DISPLAY 0.489362 (-3487 5008);
PAINT GREEN (-3487 5008);
FORCEPROP 2 LAST CDS_LIB mstr_standard
J 0
(-3425 5000);
DISPLAY 0.723404 (-3425 5000);
PAINT MONO (-3425 5000);
DISPLAY INVISIBLE (-3425 5000);
FORCEPROP 1 LAST BODY_TYPE PLUMBING
J 0
(-3425 5050);
DISPLAY 0.872340 (-3425 5050);
PAINT GREEN (-3425 5050);
DISPLAY INVISIBLE (-3425 5050);
FORCEPROP 1 LAST HDL_TAP TRUE
J 0
(-3100 4875);
DISPLAY 0.872340 (-3100 4875);
DISPLAY INVISIBLE (-3100 4875);
FORCEPROP 1 LAST PATH I189
J 0
(-3427 5000);
DISPLAY 0.872340 (-3427 5000);
PAINT GREEN (-3427 5000);
DISPLAY INVISIBLE (-3427 5000);
FORCEADD TAP..1
(-3425 4950);
FORCEPROP 3 LASTPIN (-3475 4950) SIG_NAME M_G_CPU0_SA_DQ<20>
J 0
(-3465 4960);
DISPLAY 0.659574 (-3465 4960);
PAINT MONO (-3465 4960);
DISPLAY INVISIBLE (-3465 4960);
FORCEPROP 1 LASTPIN (-3475 4950) BN 20
J 0
(-3487 4958);
DISPLAY 0.489362 (-3487 4958);
PAINT GREEN (-3487 4958);
FORCEPROP 2 LAST CDS_LIB mstr_standard
J 0
(-3425 4950);
DISPLAY 0.723404 (-3425 4950);
PAINT MONO (-3425 4950);
DISPLAY INVISIBLE (-3425 4950);
FORCEPROP 1 LAST BODY_TYPE PLUMBING
J 0
(-3425 5000);
DISPLAY 0.872340 (-3425 5000);
PAINT GREEN (-3425 5000);
DISPLAY INVISIBLE (-3425 5000);
FORCEPROP 1 LAST HDL_TAP TRUE
J 0
(-3100 4825);
DISPLAY 0.872340 (-3100 4825);
DISPLAY INVISIBLE (-3100 4825);
FORCEPROP 1 LAST PATH I190
J 0
(-3427 4950);
DISPLAY 0.872340 (-3427 4950);
PAINT GREEN (-3427 4950);
DISPLAY INVISIBLE (-3427 4950);
FORCEADD TAP..1
(-3425 4900);
FORCEPROP 3 LASTPIN (-3475 4900) SIG_NAME M_G_CPU0_SA_DQ<21>
J 0
(-3465 4910);
DISPLAY 0.659574 (-3465 4910);
PAINT MONO (-3465 4910);
DISPLAY INVISIBLE (-3465 4910);
FORCEPROP 1 LASTPIN (-3475 4900) BN 21
J 0
(-3487 4908);
DISPLAY 0.489362 (-3487 4908);
PAINT GREEN (-3487 4908);
FORCEPROP 2 LAST CDS_LIB mstr_standard
J 0
(-3425 4900);
DISPLAY 0.723404 (-3425 4900);
PAINT MONO (-3425 4900);
DISPLAY INVISIBLE (-3425 4900);
FORCEPROP 1 LAST BODY_TYPE PLUMBING
J 0
(-3425 4950);
DISPLAY 0.872340 (-3425 4950);
PAINT GREEN (-3425 4950);
DISPLAY INVISIBLE (-3425 4950);
FORCEPROP 1 LAST HDL_TAP TRUE
J 0
(-3100 4775);
DISPLAY 0.872340 (-3100 4775);
DISPLAY INVISIBLE (-3100 4775);
FORCEPROP 1 LAST PATH I191
J 0
(-3427 4900);
DISPLAY 0.872340 (-3427 4900);
PAINT GREEN (-3427 4900);
DISPLAY INVISIBLE (-3427 4900);
FORCEADD TAP..1
(-3425 4800);
FORCEPROP 3 LASTPIN (-3475 4800) SIG_NAME M_G_CPU0_SA_DQ<23>
J 0
(-3465 4810);
DISPLAY 0.659574 (-3465 4810);
PAINT MONO (-3465 4810);
DISPLAY INVISIBLE (-3465 4810);
FORCEPROP 1 LASTPIN (-3475 4800) BN 23
J 0
(-3487 4808);
DISPLAY 0.489362 (-3487 4808);
PAINT GREEN (-3487 4808);
FORCEPROP 2 LAST CDS_LIB mstr_standard
J 0
(-3425 4800);
DISPLAY 0.723404 (-3425 4800);
PAINT MONO (-3425 4800);
DISPLAY INVISIBLE (-3425 4800);
FORCEPROP 1 LAST BODY_TYPE PLUMBING
J 0
(-3425 4850);
DISPLAY 0.872340 (-3425 4850);
PAINT GREEN (-3425 4850);
DISPLAY INVISIBLE (-3425 4850);
FORCEPROP 1 LAST HDL_TAP TRUE
J 0
(-3100 4675);
DISPLAY 0.872340 (-3100 4675);
DISPLAY INVISIBLE (-3100 4675);
FORCEPROP 1 LAST PATH I192
J 0
(-3427 4800);
DISPLAY 0.872340 (-3427 4800);
PAINT GREEN (-3427 4800);
DISPLAY INVISIBLE (-3427 4800);
FORCEADD TAP..1
(-3425 4850);
FORCEPROP 3 LASTPIN (-3475 4850) SIG_NAME M_G_CPU0_SA_DQ<22>
J 0
(-3465 4860);
DISPLAY 0.659574 (-3465 4860);
PAINT MONO (-3465 4860);
DISPLAY INVISIBLE (-3465 4860);
FORCEPROP 1 LASTPIN (-3475 4850) BN 22
J 0
(-3487 4858);
DISPLAY 0.489362 (-3487 4858);
PAINT GREEN (-3487 4858);
FORCEPROP 2 LAST CDS_LIB mstr_standard
J 0
(-3425 4850);
DISPLAY 0.723404 (-3425 4850);
PAINT MONO (-3425 4850);
DISPLAY INVISIBLE (-3425 4850);
FORCEPROP 1 LAST BODY_TYPE PLUMBING
J 0
(-3425 4900);
DISPLAY 0.872340 (-3425 4900);
PAINT GREEN (-3425 4900);
DISPLAY INVISIBLE (-3425 4900);
FORCEPROP 1 LAST HDL_TAP TRUE
J 0
(-3100 4725);
DISPLAY 0.872340 (-3100 4725);
DISPLAY INVISIBLE (-3100 4725);
FORCEPROP 1 LAST PATH I193
J 0
(-3427 4850);
DISPLAY 0.872340 (-3427 4850);
PAINT GREEN (-3427 4850);
DISPLAY INVISIBLE (-3427 4850);
FORCEADD TAP..1
(-3425 4700);
FORCEPROP 3 LASTPIN (-3475 4700) SIG_NAME M_G_CPU0_SA_DQ<24>
J 0
(-3465 4710);
DISPLAY 0.659574 (-3465 4710);
PAINT MONO (-3465 4710);
DISPLAY INVISIBLE (-3465 4710);
FORCEPROP 1 LASTPIN (-3475 4700) BN 24
J 0
(-3487 4708);
DISPLAY 0.489362 (-3487 4708);
PAINT GREEN (-3487 4708);
FORCEPROP 2 LAST CDS_LIB mstr_standard
J 0
(-3425 4700);
DISPLAY 0.723404 (-3425 4700);
PAINT MONO (-3425 4700);
DISPLAY INVISIBLE (-3425 4700);
FORCEPROP 1 LAST BODY_TYPE PLUMBING
J 0
(-3425 4750);
DISPLAY 0.872340 (-3425 4750);
PAINT GREEN (-3425 4750);
DISPLAY INVISIBLE (-3425 4750);
FORCEPROP 1 LAST HDL_TAP TRUE
J 0
(-3100 4575);
DISPLAY 0.872340 (-3100 4575);
DISPLAY INVISIBLE (-3100 4575);
FORCEPROP 1 LAST PATH I194
J 0
(-3427 4700);
DISPLAY 0.872340 (-3427 4700);
PAINT GREEN (-3427 4700);
DISPLAY INVISIBLE (-3427 4700);
FORCEADD TAP..1
(-3425 4650);
FORCEPROP 3 LASTPIN (-3475 4650) SIG_NAME M_G_CPU0_SA_DQ<25>
J 0
(-3465 4660);
DISPLAY 0.659574 (-3465 4660);
PAINT MONO (-3465 4660);
DISPLAY INVISIBLE (-3465 4660);
FORCEPROP 1 LASTPIN (-3475 4650) BN 25
J 0
(-3487 4658);
DISPLAY 0.489362 (-3487 4658);
PAINT GREEN (-3487 4658);
FORCEPROP 2 LAST CDS_LIB mstr_standard
J 0
(-3425 4650);
DISPLAY 0.723404 (-3425 4650);
PAINT MONO (-3425 4650);
DISPLAY INVISIBLE (-3425 4650);
FORCEPROP 1 LAST BODY_TYPE PLUMBING
J 0
(-3425 4700);
DISPLAY 0.872340 (-3425 4700);
PAINT GREEN (-3425 4700);
DISPLAY INVISIBLE (-3425 4700);
FORCEPROP 1 LAST HDL_TAP TRUE
J 0
(-3100 4525);
DISPLAY 0.872340 (-3100 4525);
DISPLAY INVISIBLE (-3100 4525);
FORCEPROP 1 LAST PATH I195
J 0
(-3427 4650);
DISPLAY 0.872340 (-3427 4650);
PAINT GREEN (-3427 4650);
DISPLAY INVISIBLE (-3427 4650);
FORCEADD TAP..1
(-3425 4550);
FORCEPROP 3 LASTPIN (-3475 4550) SIG_NAME M_G_CPU0_SA_DQ<27>
J 0
(-3465 4560);
DISPLAY 0.659574 (-3465 4560);
PAINT MONO (-3465 4560);
DISPLAY INVISIBLE (-3465 4560);
FORCEPROP 1 LASTPIN (-3475 4550) BN 27
J 0
(-3487 4558);
DISPLAY 0.489362 (-3487 4558);
PAINT GREEN (-3487 4558);
FORCEPROP 2 LAST CDS_LIB mstr_standard
J 0
(-3425 4550);
DISPLAY 0.723404 (-3425 4550);
PAINT MONO (-3425 4550);
DISPLAY INVISIBLE (-3425 4550);
FORCEPROP 1 LAST BODY_TYPE PLUMBING
J 0
(-3425 4600);
DISPLAY 0.872340 (-3425 4600);
PAINT GREEN (-3425 4600);
DISPLAY INVISIBLE (-3425 4600);
FORCEPROP 1 LAST HDL_TAP TRUE
J 0
(-3100 4425);
DISPLAY 0.872340 (-3100 4425);
DISPLAY INVISIBLE (-3100 4425);
FORCEPROP 1 LAST PATH I196
J 0
(-3427 4550);
DISPLAY 0.872340 (-3427 4550);
PAINT GREEN (-3427 4550);
DISPLAY INVISIBLE (-3427 4550);
FORCEADD TAP..1
(-3425 4600);
FORCEPROP 3 LASTPIN (-3475 4600) SIG_NAME M_G_CPU0_SA_DQ<26>
J 0
(-3465 4610);
DISPLAY 0.659574 (-3465 4610);
PAINT MONO (-3465 4610);
DISPLAY INVISIBLE (-3465 4610);
FORCEPROP 1 LASTPIN (-3475 4600) BN 26
J 0
(-3487 4608);
DISPLAY 0.489362 (-3487 4608);
PAINT GREEN (-3487 4608);
FORCEPROP 2 LAST CDS_LIB mstr_standard
J 0
(-3425 4600);
DISPLAY 0.723404 (-3425 4600);
PAINT MONO (-3425 4600);
DISPLAY INVISIBLE (-3425 4600);
FORCEPROP 1 LAST BODY_TYPE PLUMBING
J 0
(-3425 4650);
DISPLAY 0.872340 (-3425 4650);
PAINT GREEN (-3425 4650);
DISPLAY INVISIBLE (-3425 4650);
FORCEPROP 1 LAST HDL_TAP TRUE
J 0
(-3100 4475);
DISPLAY 0.872340 (-3100 4475);
DISPLAY INVISIBLE (-3100 4475);
FORCEPROP 1 LAST PATH I197
J 0
(-3427 4600);
DISPLAY 0.872340 (-3427 4600);
PAINT GREEN (-3427 4600);
DISPLAY INVISIBLE (-3427 4600);
FORCEADD TAP..1
(-3425 4500);
FORCEPROP 3 LASTPIN (-3475 4500) SIG_NAME M_G_CPU0_SA_DQ<28>
J 0
(-3465 4510);
DISPLAY 0.659574 (-3465 4510);
PAINT MONO (-3465 4510);
DISPLAY INVISIBLE (-3465 4510);
FORCEPROP 1 LASTPIN (-3475 4500) BN 28
J 0
(-3487 4508);
DISPLAY 0.489362 (-3487 4508);
PAINT GREEN (-3487 4508);
FORCEPROP 2 LAST CDS_LIB mstr_standard
J 0
(-3425 4500);
DISPLAY 0.723404 (-3425 4500);
PAINT MONO (-3425 4500);
DISPLAY INVISIBLE (-3425 4500);
FORCEPROP 1 LAST BODY_TYPE PLUMBING
J 0
(-3425 4550);
DISPLAY 0.872340 (-3425 4550);
PAINT GREEN (-3425 4550);
DISPLAY INVISIBLE (-3425 4550);
FORCEPROP 1 LAST HDL_TAP TRUE
J 0
(-3100 4375);
DISPLAY 0.872340 (-3100 4375);
DISPLAY INVISIBLE (-3100 4375);
FORCEPROP 1 LAST PATH I198
J 0
(-3427 4500);
DISPLAY 0.872340 (-3427 4500);
PAINT GREEN (-3427 4500);
DISPLAY INVISIBLE (-3427 4500);
FORCEADD TAP..1
(-3425 4450);
FORCEPROP 3 LASTPIN (-3475 4450) SIG_NAME M_G_CPU0_SA_DQ<29>
J 0
(-3465 4460);
DISPLAY 0.659574 (-3465 4460);
PAINT MONO (-3465 4460);
DISPLAY INVISIBLE (-3465 4460);
FORCEPROP 1 LASTPIN (-3475 4450) BN 29
J 0
(-3487 4458);
DISPLAY 0.489362 (-3487 4458);
PAINT GREEN (-3487 4458);
FORCEPROP 2 LAST CDS_LIB mstr_standard
J 0
(-3425 4450);
DISPLAY 0.723404 (-3425 4450);
PAINT MONO (-3425 4450);
DISPLAY INVISIBLE (-3425 4450);
FORCEPROP 1 LAST BODY_TYPE PLUMBING
J 0
(-3425 4500);
DISPLAY 0.872340 (-3425 4500);
PAINT GREEN (-3425 4500);
DISPLAY INVISIBLE (-3425 4500);
FORCEPROP 1 LAST HDL_TAP TRUE
J 0
(-3100 4325);
DISPLAY 0.872340 (-3100 4325);
DISPLAY INVISIBLE (-3100 4325);
FORCEPROP 1 LAST PATH I199
J 0
(-3427 4450);
DISPLAY 0.872340 (-3427 4450);
PAINT GREEN (-3427 4450);
DISPLAY INVISIBLE (-3427 4450);
FORCEADD TAP..1
(-3425 4400);
FORCEPROP 3 LASTPIN (-3475 4400) SIG_NAME M_G_CPU0_SA_DQ<30>
J 0
(-3465 4410);
DISPLAY 0.659574 (-3465 4410);
PAINT MONO (-3465 4410);
DISPLAY INVISIBLE (-3465 4410);
FORCEPROP 1 LASTPIN (-3475 4400) BN 30
J 0
(-3487 4408);
DISPLAY 0.489362 (-3487 4408);
PAINT GREEN (-3487 4408);
FORCEPROP 2 LAST CDS_LIB mstr_standard
J 0
(-3425 4400);
DISPLAY 0.723404 (-3425 4400);
PAINT MONO (-3425 4400);
DISPLAY INVISIBLE (-3425 4400);
FORCEPROP 1 LAST BODY_TYPE PLUMBING
J 0
(-3425 4450);
DISPLAY 0.872340 (-3425 4450);
PAINT GREEN (-3425 4450);
DISPLAY INVISIBLE (-3425 4450);
FORCEPROP 1 LAST HDL_TAP TRUE
J 0
(-3100 4275);
DISPLAY 0.872340 (-3100 4275);
DISPLAY INVISIBLE (-3100 4275);
FORCEPROP 1 LAST PATH I200
J 0
(-3427 4400);
DISPLAY 0.872340 (-3427 4400);
PAINT GREEN (-3427 4400);
DISPLAY INVISIBLE (-3427 4400);
FORCEADD TAP..1
(-3425 4250);
FORCEPROP 3 LASTPIN (-3475 4250) SIG_NAME M_G_CPU0_SB_DQ<0>
J 0
(-3465 4260);
DISPLAY 0.659574 (-3465 4260);
PAINT MONO (-3465 4260);
DISPLAY INVISIBLE (-3465 4260);
FORCEPROP 1 LASTPIN (-3475 4250) BN 0
J 0
(-3487 4258);
DISPLAY 0.489362 (-3487 4258);
PAINT GREEN (-3487 4258);
FORCEPROP 2 LAST CDS_LIB mstr_standard
J 0
(-3425 4250);
DISPLAY 0.723404 (-3425 4250);
PAINT MONO (-3425 4250);
DISPLAY INVISIBLE (-3425 4250);
FORCEPROP 1 LAST BODY_TYPE PLUMBING
J 0
(-3425 4300);
DISPLAY 0.872340 (-3425 4300);
PAINT GREEN (-3425 4300);
DISPLAY INVISIBLE (-3425 4300);
FORCEPROP 1 LAST HDL_TAP TRUE
J 0
(-3100 4125);
DISPLAY 0.872340 (-3100 4125);
DISPLAY INVISIBLE (-3100 4125);
FORCEPROP 1 LAST PATH I201
J 0
(-3427 4250);
DISPLAY 0.872340 (-3427 4250);
PAINT GREEN (-3427 4250);
DISPLAY INVISIBLE (-3427 4250);
FORCEADD TAP..1
(-3425 4350);
FORCEPROP 3 LASTPIN (-3475 4350) SIG_NAME M_G_CPU0_SA_DQ<31>
J 0
(-3465 4360);
DISPLAY 0.659574 (-3465 4360);
PAINT MONO (-3465 4360);
DISPLAY INVISIBLE (-3465 4360);
FORCEPROP 1 LASTPIN (-3475 4350) BN 31
J 0
(-3487 4358);
DISPLAY 0.489362 (-3487 4358);
PAINT GREEN (-3487 4358);
FORCEPROP 2 LAST CDS_LIB mstr_standard
J 0
(-3425 4350);
DISPLAY 0.723404 (-3425 4350);
PAINT MONO (-3425 4350);
DISPLAY INVISIBLE (-3425 4350);
FORCEPROP 1 LAST BODY_TYPE PLUMBING
J 0
(-3425 4400);
DISPLAY 0.872340 (-3425 4400);
PAINT GREEN (-3425 4400);
DISPLAY INVISIBLE (-3425 4400);
FORCEPROP 1 LAST HDL_TAP TRUE
J 0
(-3100 4225);
DISPLAY 0.872340 (-3100 4225);
DISPLAY INVISIBLE (-3100 4225);
FORCEPROP 1 LAST PATH I202
J 0
(-3427 4350);
DISPLAY 0.872340 (-3427 4350);
PAINT GREEN (-3427 4350);
DISPLAY INVISIBLE (-3427 4350);
FORCEADD TAP..1
(-3425 4200);
FORCEPROP 3 LASTPIN (-3475 4200) SIG_NAME M_G_CPU0_SB_DQ<1>
J 0
(-3465 4210);
DISPLAY 0.659574 (-3465 4210);
PAINT MONO (-3465 4210);
DISPLAY INVISIBLE (-3465 4210);
FORCEPROP 1 LASTPIN (-3475 4200) BN 1
J 0
(-3487 4208);
DISPLAY 0.489362 (-3487 4208);
PAINT GREEN (-3487 4208);
FORCEPROP 2 LAST CDS_LIB mstr_standard
J 0
(-3425 4200);
DISPLAY 0.723404 (-3425 4200);
PAINT MONO (-3425 4200);
DISPLAY INVISIBLE (-3425 4200);
FORCEPROP 1 LAST BODY_TYPE PLUMBING
J 0
(-3425 4250);
DISPLAY 0.872340 (-3425 4250);
PAINT GREEN (-3425 4250);
DISPLAY INVISIBLE (-3425 4250);
FORCEPROP 1 LAST HDL_TAP TRUE
J 0
(-3100 4075);
DISPLAY 0.872340 (-3100 4075);
DISPLAY INVISIBLE (-3100 4075);
FORCEPROP 1 LAST PATH I203
J 0
(-3427 4200);
DISPLAY 0.872340 (-3427 4200);
PAINT GREEN (-3427 4200);
DISPLAY INVISIBLE (-3427 4200);
FORCEADD TAP..1
(-3425 4150);
FORCEPROP 3 LASTPIN (-3475 4150) SIG_NAME M_G_CPU0_SB_DQ<2>
J 0
(-3465 4160);
DISPLAY 0.659574 (-3465 4160);
PAINT MONO (-3465 4160);
DISPLAY INVISIBLE (-3465 4160);
FORCEPROP 1 LASTPIN (-3475 4150) BN 2
J 0
(-3487 4158);
DISPLAY 0.489362 (-3487 4158);
PAINT GREEN (-3487 4158);
FORCEPROP 2 LAST CDS_LIB mstr_standard
J 0
(-3425 4150);
DISPLAY 0.723404 (-3425 4150);
PAINT MONO (-3425 4150);
DISPLAY INVISIBLE (-3425 4150);
FORCEPROP 1 LAST BODY_TYPE PLUMBING
J 0
(-3425 4200);
DISPLAY 0.872340 (-3425 4200);
PAINT GREEN (-3425 4200);
DISPLAY INVISIBLE (-3425 4200);
FORCEPROP 1 LAST HDL_TAP TRUE
J 0
(-3100 4025);
DISPLAY 0.872340 (-3100 4025);
DISPLAY INVISIBLE (-3100 4025);
FORCEPROP 1 LAST PATH I204
J 0
(-3427 4150);
DISPLAY 0.872340 (-3427 4150);
PAINT GREEN (-3427 4150);
DISPLAY INVISIBLE (-3427 4150);
FORCEADD TAP..1
(-3425 4100);
FORCEPROP 3 LASTPIN (-3475 4100) SIG_NAME M_G_CPU0_SB_DQ<3>
J 0
(-3465 4110);
DISPLAY 0.659574 (-3465 4110);
PAINT MONO (-3465 4110);
DISPLAY INVISIBLE (-3465 4110);
FORCEPROP 1 LASTPIN (-3475 4100) BN 3
J 0
(-3487 4108);
DISPLAY 0.489362 (-3487 4108);
PAINT GREEN (-3487 4108);
FORCEPROP 2 LAST CDS_LIB mstr_standard
J 0
(-3425 4100);
DISPLAY 0.723404 (-3425 4100);
PAINT MONO (-3425 4100);
DISPLAY INVISIBLE (-3425 4100);
FORCEPROP 1 LAST BODY_TYPE PLUMBING
J 0
(-3425 4150);
DISPLAY 0.872340 (-3425 4150);
PAINT GREEN (-3425 4150);
DISPLAY INVISIBLE (-3425 4150);
FORCEPROP 1 LAST HDL_TAP TRUE
J 0
(-3100 3975);
DISPLAY 0.872340 (-3100 3975);
DISPLAY INVISIBLE (-3100 3975);
FORCEPROP 1 LAST PATH I205
J 0
(-3427 4100);
DISPLAY 0.872340 (-3427 4100);
PAINT GREEN (-3427 4100);
DISPLAY INVISIBLE (-3427 4100);
FORCEADD OFFPAGE..6
R 2
(-2825 2500);
FORCEPROP 2 LAST $XR0 91 
J 0
(-2611 2500);
DISPLAY 0.638298 (-2611 2500);
PAINT MONO (-2611 2500);
FORCEPROP 2 LAST PATH I206
J 0
(-2600 2550);
DISPLAY 1.021277 (-2600 2550);
DISPLAY INVISIBLE (-2600 2550);
FORCEPROP 1 LAST COMMENT_BODY TRUE
J 2
(-2925 2425);
DISPLAY 0.872340 (-2925 2425);
PAINT GREEN (-2925 2425);
DISPLAY INVISIBLE (-2925 2425);
FORCEPROP 1 LAST OFFPAGE TRUE
J 2
(-3150 2375);
DISPLAY 0.872340 (-3150 2375);
PAINT GREEN (-3150 2375);
DISPLAY INVISIBLE (-3150 2375);
FORCEPROP 2 LAST CDS_LIB mstr_standard
J 2
(-2825 2500);
DISPLAY 0.723404 (-2825 2500);
PAINT MONO (-2825 2500);
DISPLAY INVISIBLE (-2825 2500);
FORCEADD TAP..1
(-3425 4050);
FORCEPROP 3 LASTPIN (-3475 4050) SIG_NAME M_G_CPU0_SB_DQ<4>
J 0
(-3465 4060);
DISPLAY 0.659574 (-3465 4060);
PAINT MONO (-3465 4060);
DISPLAY INVISIBLE (-3465 4060);
FORCEPROP 1 LASTPIN (-3475 4050) BN 4
J 0
(-3487 4058);
DISPLAY 0.489362 (-3487 4058);
PAINT GREEN (-3487 4058);
FORCEPROP 2 LAST CDS_LIB mstr_standard
J 0
(-3425 4050);
DISPLAY 0.723404 (-3425 4050);
PAINT MONO (-3425 4050);
DISPLAY INVISIBLE (-3425 4050);
FORCEPROP 1 LAST BODY_TYPE PLUMBING
J 0
(-3425 4100);
DISPLAY 0.872340 (-3425 4100);
PAINT GREEN (-3425 4100);
DISPLAY INVISIBLE (-3425 4100);
FORCEPROP 1 LAST HDL_TAP TRUE
J 0
(-3100 3925);
DISPLAY 0.872340 (-3100 3925);
DISPLAY INVISIBLE (-3100 3925);
FORCEPROP 1 LAST PATH I207
J 0
(-3427 4050);
DISPLAY 0.872340 (-3427 4050);
PAINT GREEN (-3427 4050);
DISPLAY INVISIBLE (-3427 4050);
FORCEADD TAP..1
(-3425 4000);
FORCEPROP 3 LASTPIN (-3475 4000) SIG_NAME M_G_CPU0_SB_DQ<5>
J 0
(-3465 4010);
DISPLAY 0.659574 (-3465 4010);
PAINT MONO (-3465 4010);
DISPLAY INVISIBLE (-3465 4010);
FORCEPROP 1 LASTPIN (-3475 4000) BN 5
J 0
(-3487 4008);
DISPLAY 0.489362 (-3487 4008);
PAINT GREEN (-3487 4008);
FORCEPROP 2 LAST CDS_LIB mstr_standard
J 0
(-3425 4000);
DISPLAY 0.723404 (-3425 4000);
PAINT MONO (-3425 4000);
DISPLAY INVISIBLE (-3425 4000);
FORCEPROP 1 LAST BODY_TYPE PLUMBING
J 0
(-3425 4050);
DISPLAY 0.872340 (-3425 4050);
PAINT GREEN (-3425 4050);
DISPLAY INVISIBLE (-3425 4050);
FORCEPROP 1 LAST HDL_TAP TRUE
J 0
(-3100 3875);
DISPLAY 0.872340 (-3100 3875);
DISPLAY INVISIBLE (-3100 3875);
FORCEPROP 1 LAST PATH I208
J 0
(-3427 4000);
DISPLAY 0.872340 (-3427 4000);
PAINT GREEN (-3427 4000);
DISPLAY INVISIBLE (-3427 4000);
FORCEADD TAP..1
(-3425 3900);
FORCEPROP 3 LASTPIN (-3475 3900) SIG_NAME M_G_CPU0_SB_DQ<7>
J 0
(-3465 3910);
DISPLAY 0.659574 (-3465 3910);
PAINT MONO (-3465 3910);
DISPLAY INVISIBLE (-3465 3910);
FORCEPROP 1 LASTPIN (-3475 3900) BN 7
J 0
(-3487 3908);
DISPLAY 0.489362 (-3487 3908);
PAINT GREEN (-3487 3908);
FORCEPROP 2 LAST CDS_LIB mstr_standard
J 0
(-3425 3900);
DISPLAY 0.723404 (-3425 3900);
PAINT MONO (-3425 3900);
DISPLAY INVISIBLE (-3425 3900);
FORCEPROP 1 LAST BODY_TYPE PLUMBING
J 0
(-3425 3950);
DISPLAY 0.872340 (-3425 3950);
PAINT GREEN (-3425 3950);
DISPLAY INVISIBLE (-3425 3950);
FORCEPROP 1 LAST HDL_TAP TRUE
J 0
(-3100 3775);
DISPLAY 0.872340 (-3100 3775);
DISPLAY INVISIBLE (-3100 3775);
FORCEPROP 1 LAST PATH I209
J 0
(-3427 3900);
DISPLAY 0.872340 (-3427 3900);
PAINT GREEN (-3427 3900);
DISPLAY INVISIBLE (-3427 3900);
FORCEADD TAP..1
(-3425 3950);
FORCEPROP 3 LASTPIN (-3475 3950) SIG_NAME M_G_CPU0_SB_DQ<6>
J 0
(-3465 3960);
DISPLAY 0.659574 (-3465 3960);
PAINT MONO (-3465 3960);
DISPLAY INVISIBLE (-3465 3960);
FORCEPROP 1 LASTPIN (-3475 3950) BN 6
J 0
(-3487 3958);
DISPLAY 0.489362 (-3487 3958);
PAINT GREEN (-3487 3958);
FORCEPROP 2 LAST CDS_LIB mstr_standard
J 0
(-3425 3950);
DISPLAY 0.723404 (-3425 3950);
PAINT MONO (-3425 3950);
DISPLAY INVISIBLE (-3425 3950);
FORCEPROP 1 LAST BODY_TYPE PLUMBING
J 0
(-3425 4000);
DISPLAY 0.872340 (-3425 4000);
PAINT GREEN (-3425 4000);
DISPLAY INVISIBLE (-3425 4000);
FORCEPROP 1 LAST HDL_TAP TRUE
J 0
(-3100 3825);
DISPLAY 0.872340 (-3100 3825);
DISPLAY INVISIBLE (-3100 3825);
FORCEPROP 1 LAST PATH I210
J 0
(-3427 3950);
DISPLAY 0.872340 (-3427 3950);
PAINT GREEN (-3427 3950);
DISPLAY INVISIBLE (-3427 3950);
FORCEADD TAP..1
(-3425 3800);
FORCEPROP 3 LASTPIN (-3475 3800) SIG_NAME M_G_CPU0_SB_DQ<8>
J 0
(-3465 3810);
DISPLAY 0.659574 (-3465 3810);
PAINT MONO (-3465 3810);
DISPLAY INVISIBLE (-3465 3810);
FORCEPROP 1 LASTPIN (-3475 3800) BN 8
J 0
(-3487 3808);
DISPLAY 0.489362 (-3487 3808);
PAINT GREEN (-3487 3808);
FORCEPROP 2 LAST CDS_LIB mstr_standard
J 0
(-3425 3800);
DISPLAY 0.723404 (-3425 3800);
PAINT MONO (-3425 3800);
DISPLAY INVISIBLE (-3425 3800);
FORCEPROP 1 LAST BODY_TYPE PLUMBING
J 0
(-3425 3850);
DISPLAY 0.872340 (-3425 3850);
PAINT GREEN (-3425 3850);
DISPLAY INVISIBLE (-3425 3850);
FORCEPROP 1 LAST HDL_TAP TRUE
J 0
(-3100 3675);
DISPLAY 0.872340 (-3100 3675);
DISPLAY INVISIBLE (-3100 3675);
FORCEPROP 1 LAST PATH I211
J 0
(-3427 3800);
DISPLAY 0.872340 (-3427 3800);
PAINT GREEN (-3427 3800);
DISPLAY INVISIBLE (-3427 3800);
FORCEADD TAP..1
(-3425 3750);
FORCEPROP 3 LASTPIN (-3475 3750) SIG_NAME M_G_CPU0_SB_DQ<9>
J 0
(-3465 3760);
DISPLAY 0.659574 (-3465 3760);
PAINT MONO (-3465 3760);
DISPLAY INVISIBLE (-3465 3760);
FORCEPROP 1 LASTPIN (-3475 3750) BN 9
J 0
(-3487 3758);
DISPLAY 0.489362 (-3487 3758);
PAINT GREEN (-3487 3758);
FORCEPROP 2 LAST CDS_LIB mstr_standard
J 0
(-3425 3750);
DISPLAY 0.723404 (-3425 3750);
PAINT MONO (-3425 3750);
DISPLAY INVISIBLE (-3425 3750);
FORCEPROP 1 LAST BODY_TYPE PLUMBING
J 0
(-3425 3800);
DISPLAY 0.872340 (-3425 3800);
PAINT GREEN (-3425 3800);
DISPLAY INVISIBLE (-3425 3800);
FORCEPROP 1 LAST HDL_TAP TRUE
J 0
(-3100 3625);
DISPLAY 0.872340 (-3100 3625);
DISPLAY INVISIBLE (-3100 3625);
FORCEPROP 1 LAST PATH I212
J 0
(-3427 3750);
DISPLAY 0.872340 (-3427 3750);
PAINT GREEN (-3427 3750);
DISPLAY INVISIBLE (-3427 3750);
FORCEADD TAP..1
(-3425 3650);
FORCEPROP 3 LASTPIN (-3475 3650) SIG_NAME M_G_CPU0_SB_DQ<11>
J 0
(-3465 3660);
DISPLAY 0.659574 (-3465 3660);
PAINT MONO (-3465 3660);
DISPLAY INVISIBLE (-3465 3660);
FORCEPROP 1 LASTPIN (-3475 3650) BN 11
J 0
(-3487 3658);
DISPLAY 0.489362 (-3487 3658);
PAINT GREEN (-3487 3658);
FORCEPROP 2 LAST CDS_LIB mstr_standard
J 0
(-3425 3650);
DISPLAY 0.723404 (-3425 3650);
PAINT MONO (-3425 3650);
DISPLAY INVISIBLE (-3425 3650);
FORCEPROP 1 LAST BODY_TYPE PLUMBING
J 0
(-3425 3700);
DISPLAY 0.872340 (-3425 3700);
PAINT GREEN (-3425 3700);
DISPLAY INVISIBLE (-3425 3700);
FORCEPROP 1 LAST HDL_TAP TRUE
J 0
(-3100 3525);
DISPLAY 0.872340 (-3100 3525);
DISPLAY INVISIBLE (-3100 3525);
FORCEPROP 1 LAST PATH I213
J 0
(-3427 3650);
DISPLAY 0.872340 (-3427 3650);
PAINT GREEN (-3427 3650);
DISPLAY INVISIBLE (-3427 3650);
FORCEADD TAP..1
(-3425 3700);
FORCEPROP 3 LASTPIN (-3475 3700) SIG_NAME M_G_CPU0_SB_DQ<10>
J 0
(-3465 3710);
DISPLAY 0.659574 (-3465 3710);
PAINT MONO (-3465 3710);
DISPLAY INVISIBLE (-3465 3710);
FORCEPROP 1 LASTPIN (-3475 3700) BN 10
J 0
(-3487 3708);
DISPLAY 0.489362 (-3487 3708);
PAINT GREEN (-3487 3708);
FORCEPROP 2 LAST CDS_LIB mstr_standard
J 0
(-3425 3700);
DISPLAY 0.723404 (-3425 3700);
PAINT MONO (-3425 3700);
DISPLAY INVISIBLE (-3425 3700);
FORCEPROP 1 LAST BODY_TYPE PLUMBING
J 0
(-3425 3750);
DISPLAY 0.872340 (-3425 3750);
PAINT GREEN (-3425 3750);
DISPLAY INVISIBLE (-3425 3750);
FORCEPROP 1 LAST HDL_TAP TRUE
J 0
(-3100 3575);
DISPLAY 0.872340 (-3100 3575);
DISPLAY INVISIBLE (-3100 3575);
FORCEPROP 1 LAST PATH I214
J 0
(-3427 3700);
DISPLAY 0.872340 (-3427 3700);
PAINT GREEN (-3427 3700);
DISPLAY INVISIBLE (-3427 3700);
FORCEADD TAP..1
(-3425 3600);
FORCEPROP 3 LASTPIN (-3475 3600) SIG_NAME M_G_CPU0_SB_DQ<12>
J 0
(-3465 3610);
DISPLAY 0.659574 (-3465 3610);
PAINT MONO (-3465 3610);
DISPLAY INVISIBLE (-3465 3610);
FORCEPROP 1 LASTPIN (-3475 3600) BN 12
J 0
(-3487 3608);
DISPLAY 0.489362 (-3487 3608);
PAINT GREEN (-3487 3608);
FORCEPROP 2 LAST CDS_LIB mstr_standard
J 0
(-3425 3600);
DISPLAY 0.723404 (-3425 3600);
PAINT MONO (-3425 3600);
DISPLAY INVISIBLE (-3425 3600);
FORCEPROP 1 LAST BODY_TYPE PLUMBING
J 0
(-3425 3650);
DISPLAY 0.872340 (-3425 3650);
PAINT GREEN (-3425 3650);
DISPLAY INVISIBLE (-3425 3650);
FORCEPROP 1 LAST HDL_TAP TRUE
J 0
(-3100 3475);
DISPLAY 0.872340 (-3100 3475);
DISPLAY INVISIBLE (-3100 3475);
FORCEPROP 1 LAST PATH I215
J 0
(-3427 3600);
DISPLAY 0.872340 (-3427 3600);
PAINT GREEN (-3427 3600);
DISPLAY INVISIBLE (-3427 3600);
FORCEADD TAP..1
(-3425 3550);
FORCEPROP 3 LASTPIN (-3475 3550) SIG_NAME M_G_CPU0_SB_DQ<13>
J 0
(-3465 3560);
DISPLAY 0.659574 (-3465 3560);
PAINT MONO (-3465 3560);
DISPLAY INVISIBLE (-3465 3560);
FORCEPROP 1 LASTPIN (-3475 3550) BN 13
J 0
(-3487 3558);
DISPLAY 0.489362 (-3487 3558);
PAINT GREEN (-3487 3558);
FORCEPROP 2 LAST CDS_LIB mstr_standard
J 0
(-3425 3550);
DISPLAY 0.723404 (-3425 3550);
PAINT MONO (-3425 3550);
DISPLAY INVISIBLE (-3425 3550);
FORCEPROP 1 LAST BODY_TYPE PLUMBING
J 0
(-3425 3600);
DISPLAY 0.872340 (-3425 3600);
PAINT GREEN (-3425 3600);
DISPLAY INVISIBLE (-3425 3600);
FORCEPROP 1 LAST HDL_TAP TRUE
J 0
(-3100 3425);
DISPLAY 0.872340 (-3100 3425);
DISPLAY INVISIBLE (-3100 3425);
FORCEPROP 1 LAST PATH I216
J 0
(-3427 3550);
DISPLAY 0.872340 (-3427 3550);
PAINT GREEN (-3427 3550);
DISPLAY INVISIBLE (-3427 3550);
FORCEADD TAP..1
(-3425 3500);
FORCEPROP 3 LASTPIN (-3475 3500) SIG_NAME M_G_CPU0_SB_DQ<14>
J 0
(-3465 3510);
DISPLAY 0.659574 (-3465 3510);
PAINT MONO (-3465 3510);
DISPLAY INVISIBLE (-3465 3510);
FORCEPROP 1 LASTPIN (-3475 3500) BN 14
J 0
(-3487 3508);
DISPLAY 0.489362 (-3487 3508);
PAINT GREEN (-3487 3508);
FORCEPROP 2 LAST CDS_LIB mstr_standard
J 0
(-3425 3500);
DISPLAY 0.723404 (-3425 3500);
PAINT MONO (-3425 3500);
DISPLAY INVISIBLE (-3425 3500);
FORCEPROP 1 LAST BODY_TYPE PLUMBING
J 0
(-3425 3550);
DISPLAY 0.872340 (-3425 3550);
PAINT GREEN (-3425 3550);
DISPLAY INVISIBLE (-3425 3550);
FORCEPROP 1 LAST HDL_TAP TRUE
J 0
(-3100 3375);
DISPLAY 0.872340 (-3100 3375);
DISPLAY INVISIBLE (-3100 3375);
FORCEPROP 1 LAST PATH I217
J 0
(-3427 3500);
DISPLAY 0.872340 (-3427 3500);
PAINT GREEN (-3427 3500);
DISPLAY INVISIBLE (-3427 3500);
FORCEADD TAP..1
(-3425 3350);
FORCEPROP 3 LASTPIN (-3475 3350) SIG_NAME M_G_CPU0_SB_DQ<16>
J 0
(-3465 3360);
DISPLAY 0.659574 (-3465 3360);
PAINT MONO (-3465 3360);
DISPLAY INVISIBLE (-3465 3360);
FORCEPROP 1 LASTPIN (-3475 3350) BN 16
J 0
(-3487 3358);
DISPLAY 0.489362 (-3487 3358);
PAINT GREEN (-3487 3358);
FORCEPROP 2 LAST CDS_LIB mstr_standard
J 0
(-3425 3350);
DISPLAY 0.723404 (-3425 3350);
PAINT MONO (-3425 3350);
DISPLAY INVISIBLE (-3425 3350);
FORCEPROP 1 LAST BODY_TYPE PLUMBING
J 0
(-3425 3400);
DISPLAY 0.872340 (-3425 3400);
PAINT GREEN (-3425 3400);
DISPLAY INVISIBLE (-3425 3400);
FORCEPROP 1 LAST HDL_TAP TRUE
J 0
(-3100 3225);
DISPLAY 0.872340 (-3100 3225);
DISPLAY INVISIBLE (-3100 3225);
FORCEPROP 1 LAST PATH I218
J 0
(-3427 3350);
DISPLAY 0.872340 (-3427 3350);
PAINT GREEN (-3427 3350);
DISPLAY INVISIBLE (-3427 3350);
FORCEADD TAP..1
(-3425 3450);
FORCEPROP 3 LASTPIN (-3475 3450) SIG_NAME M_G_CPU0_SB_DQ<15>
J 0
(-3465 3460);
DISPLAY 0.659574 (-3465 3460);
PAINT MONO (-3465 3460);
DISPLAY INVISIBLE (-3465 3460);
FORCEPROP 1 LASTPIN (-3475 3450) BN 15
J 0
(-3487 3458);
DISPLAY 0.489362 (-3487 3458);
PAINT GREEN (-3487 3458);
FORCEPROP 2 LAST CDS_LIB mstr_standard
J 0
(-3425 3450);
DISPLAY 0.723404 (-3425 3450);
PAINT MONO (-3425 3450);
DISPLAY INVISIBLE (-3425 3450);
FORCEPROP 1 LAST BODY_TYPE PLUMBING
J 0
(-3425 3500);
DISPLAY 0.872340 (-3425 3500);
PAINT GREEN (-3425 3500);
DISPLAY INVISIBLE (-3425 3500);
FORCEPROP 1 LAST HDL_TAP TRUE
J 0
(-3100 3325);
DISPLAY 0.872340 (-3100 3325);
DISPLAY INVISIBLE (-3100 3325);
FORCEPROP 1 LAST PATH I219
J 0
(-3427 3450);
DISPLAY 0.872340 (-3427 3450);
PAINT GREEN (-3427 3450);
DISPLAY INVISIBLE (-3427 3450);
FORCEADD TAP..1
(-3425 3300);
FORCEPROP 3 LASTPIN (-3475 3300) SIG_NAME M_G_CPU0_SB_DQ<17>
J 0
(-3465 3310);
DISPLAY 0.659574 (-3465 3310);
PAINT MONO (-3465 3310);
DISPLAY INVISIBLE (-3465 3310);
FORCEPROP 1 LASTPIN (-3475 3300) BN 17
J 0
(-3487 3308);
DISPLAY 0.489362 (-3487 3308);
PAINT GREEN (-3487 3308);
FORCEPROP 2 LAST CDS_LIB mstr_standard
J 0
(-3425 3300);
DISPLAY 0.723404 (-3425 3300);
PAINT MONO (-3425 3300);
DISPLAY INVISIBLE (-3425 3300);
FORCEPROP 1 LAST BODY_TYPE PLUMBING
J 0
(-3425 3350);
DISPLAY 0.872340 (-3425 3350);
PAINT GREEN (-3425 3350);
DISPLAY INVISIBLE (-3425 3350);
FORCEPROP 1 LAST HDL_TAP TRUE
J 0
(-3100 3175);
DISPLAY 0.872340 (-3100 3175);
DISPLAY INVISIBLE (-3100 3175);
FORCEPROP 1 LAST PATH I220
J 0
(-3427 3300);
DISPLAY 0.872340 (-3427 3300);
PAINT GREEN (-3427 3300);
DISPLAY INVISIBLE (-3427 3300);
FORCEADD TAP..1
(-3425 3250);
FORCEPROP 3 LASTPIN (-3475 3250) SIG_NAME M_G_CPU0_SB_DQ<18>
J 0
(-3465 3260);
DISPLAY 0.659574 (-3465 3260);
PAINT MONO (-3465 3260);
DISPLAY INVISIBLE (-3465 3260);
FORCEPROP 1 LASTPIN (-3475 3250) BN 18
J 0
(-3487 3258);
DISPLAY 0.489362 (-3487 3258);
PAINT GREEN (-3487 3258);
FORCEPROP 2 LAST CDS_LIB mstr_standard
J 0
(-3425 3250);
DISPLAY 0.723404 (-3425 3250);
PAINT MONO (-3425 3250);
DISPLAY INVISIBLE (-3425 3250);
FORCEPROP 1 LAST BODY_TYPE PLUMBING
J 0
(-3425 3300);
DISPLAY 0.872340 (-3425 3300);
PAINT GREEN (-3425 3300);
DISPLAY INVISIBLE (-3425 3300);
FORCEPROP 1 LAST HDL_TAP TRUE
J 0
(-3100 3125);
DISPLAY 0.872340 (-3100 3125);
DISPLAY INVISIBLE (-3100 3125);
FORCEPROP 1 LAST PATH I221
J 0
(-3427 3250);
DISPLAY 0.872340 (-3427 3250);
PAINT GREEN (-3427 3250);
DISPLAY INVISIBLE (-3427 3250);
FORCEADD TAP..1
(-3425 3200);
FORCEPROP 3 LASTPIN (-3475 3200) SIG_NAME M_G_CPU0_SB_DQ<19>
J 0
(-3465 3210);
DISPLAY 0.659574 (-3465 3210);
PAINT MONO (-3465 3210);
DISPLAY INVISIBLE (-3465 3210);
FORCEPROP 1 LASTPIN (-3475 3200) BN 19
J 0
(-3487 3208);
DISPLAY 0.489362 (-3487 3208);
PAINT GREEN (-3487 3208);
FORCEPROP 2 LAST CDS_LIB mstr_standard
J 0
(-3425 3200);
DISPLAY 0.723404 (-3425 3200);
PAINT MONO (-3425 3200);
DISPLAY INVISIBLE (-3425 3200);
FORCEPROP 1 LAST BODY_TYPE PLUMBING
J 0
(-3425 3250);
DISPLAY 0.872340 (-3425 3250);
PAINT GREEN (-3425 3250);
DISPLAY INVISIBLE (-3425 3250);
FORCEPROP 1 LAST HDL_TAP TRUE
J 0
(-3100 3075);
DISPLAY 0.872340 (-3100 3075);
DISPLAY INVISIBLE (-3100 3075);
FORCEPROP 1 LAST PATH I222
J 0
(-3427 3200);
DISPLAY 0.872340 (-3427 3200);
PAINT GREEN (-3427 3200);
DISPLAY INVISIBLE (-3427 3200);
FORCEADD TAP..1
(-3425 3150);
FORCEPROP 3 LASTPIN (-3475 3150) SIG_NAME M_G_CPU0_SB_DQ<20>
J 0
(-3465 3160);
DISPLAY 0.659574 (-3465 3160);
PAINT MONO (-3465 3160);
DISPLAY INVISIBLE (-3465 3160);
FORCEPROP 1 LASTPIN (-3475 3150) BN 20
J 0
(-3487 3158);
DISPLAY 0.489362 (-3487 3158);
PAINT GREEN (-3487 3158);
FORCEPROP 2 LAST CDS_LIB mstr_standard
J 0
(-3425 3150);
DISPLAY 0.723404 (-3425 3150);
PAINT MONO (-3425 3150);
DISPLAY INVISIBLE (-3425 3150);
FORCEPROP 1 LAST BODY_TYPE PLUMBING
J 0
(-3425 3200);
DISPLAY 0.872340 (-3425 3200);
PAINT GREEN (-3425 3200);
DISPLAY INVISIBLE (-3425 3200);
FORCEPROP 1 LAST HDL_TAP TRUE
J 0
(-3100 3025);
DISPLAY 0.872340 (-3100 3025);
DISPLAY INVISIBLE (-3100 3025);
FORCEPROP 1 LAST PATH I223
J 0
(-3427 3150);
DISPLAY 0.872340 (-3427 3150);
PAINT GREEN (-3427 3150);
DISPLAY INVISIBLE (-3427 3150);
FORCEADD TAP..1
(-3425 3100);
FORCEPROP 3 LASTPIN (-3475 3100) SIG_NAME M_G_CPU0_SB_DQ<21>
J 0
(-3465 3110);
DISPLAY 0.659574 (-3465 3110);
PAINT MONO (-3465 3110);
DISPLAY INVISIBLE (-3465 3110);
FORCEPROP 1 LASTPIN (-3475 3100) BN 21
J 0
(-3487 3108);
DISPLAY 0.489362 (-3487 3108);
PAINT GREEN (-3487 3108);
FORCEPROP 2 LAST CDS_LIB mstr_standard
J 0
(-3425 3100);
DISPLAY 0.723404 (-3425 3100);
PAINT MONO (-3425 3100);
DISPLAY INVISIBLE (-3425 3100);
FORCEPROP 1 LAST BODY_TYPE PLUMBING
J 0
(-3425 3150);
DISPLAY 0.872340 (-3425 3150);
PAINT GREEN (-3425 3150);
DISPLAY INVISIBLE (-3425 3150);
FORCEPROP 1 LAST HDL_TAP TRUE
J 0
(-3100 2975);
DISPLAY 0.872340 (-3100 2975);
DISPLAY INVISIBLE (-3100 2975);
FORCEPROP 1 LAST PATH I224
J 0
(-3427 3100);
DISPLAY 0.872340 (-3427 3100);
PAINT GREEN (-3427 3100);
DISPLAY INVISIBLE (-3427 3100);
FORCEADD TAP..1
(-3425 3050);
FORCEPROP 3 LASTPIN (-3475 3050) SIG_NAME M_G_CPU0_SB_DQ<22>
J 0
(-3465 3060);
DISPLAY 0.659574 (-3465 3060);
PAINT MONO (-3465 3060);
DISPLAY INVISIBLE (-3465 3060);
FORCEPROP 1 LASTPIN (-3475 3050) BN 22
J 0
(-3487 3058);
DISPLAY 0.489362 (-3487 3058);
PAINT GREEN (-3487 3058);
FORCEPROP 2 LAST CDS_LIB mstr_standard
J 0
(-3425 3050);
DISPLAY 0.723404 (-3425 3050);
PAINT MONO (-3425 3050);
DISPLAY INVISIBLE (-3425 3050);
FORCEPROP 1 LAST BODY_TYPE PLUMBING
J 0
(-3425 3100);
DISPLAY 0.872340 (-3425 3100);
PAINT GREEN (-3425 3100);
DISPLAY INVISIBLE (-3425 3100);
FORCEPROP 1 LAST HDL_TAP TRUE
J 0
(-3100 2925);
DISPLAY 0.872340 (-3100 2925);
DISPLAY INVISIBLE (-3100 2925);
FORCEPROP 1 LAST PATH I225
J 0
(-3427 3050);
DISPLAY 0.872340 (-3427 3050);
PAINT GREEN (-3427 3050);
DISPLAY INVISIBLE (-3427 3050);
FORCEADD TAP..1
(-3425 3000);
FORCEPROP 3 LASTPIN (-3475 3000) SIG_NAME M_G_CPU0_SB_DQ<23>
J 0
(-3465 3010);
DISPLAY 0.659574 (-3465 3010);
PAINT MONO (-3465 3010);
DISPLAY INVISIBLE (-3465 3010);
FORCEPROP 1 LASTPIN (-3475 3000) BN 23
J 0
(-3487 3008);
DISPLAY 0.489362 (-3487 3008);
PAINT GREEN (-3487 3008);
FORCEPROP 2 LAST CDS_LIB mstr_standard
J 0
(-3425 3000);
DISPLAY 0.723404 (-3425 3000);
PAINT MONO (-3425 3000);
DISPLAY INVISIBLE (-3425 3000);
FORCEPROP 1 LAST BODY_TYPE PLUMBING
J 0
(-3425 3050);
DISPLAY 0.872340 (-3425 3050);
PAINT GREEN (-3425 3050);
DISPLAY INVISIBLE (-3425 3050);
FORCEPROP 1 LAST HDL_TAP TRUE
J 0
(-3100 2875);
DISPLAY 0.872340 (-3100 2875);
DISPLAY INVISIBLE (-3100 2875);
FORCEPROP 1 LAST PATH I226
J 0
(-3427 3000);
DISPLAY 0.872340 (-3427 3000);
PAINT GREEN (-3427 3000);
DISPLAY INVISIBLE (-3427 3000);
FORCEADD TAP..1
(-3425 2900);
FORCEPROP 3 LASTPIN (-3475 2900) SIG_NAME M_G_CPU0_SB_DQ<24>
J 0
(-3465 2910);
DISPLAY 0.659574 (-3465 2910);
PAINT MONO (-3465 2910);
DISPLAY INVISIBLE (-3465 2910);
FORCEPROP 1 LASTPIN (-3475 2900) BN 24
J 0
(-3487 2908);
DISPLAY 0.489362 (-3487 2908);
PAINT GREEN (-3487 2908);
FORCEPROP 2 LAST CDS_LIB mstr_standard
J 0
(-3425 2900);
DISPLAY 0.723404 (-3425 2900);
PAINT MONO (-3425 2900);
DISPLAY INVISIBLE (-3425 2900);
FORCEPROP 1 LAST BODY_TYPE PLUMBING
J 0
(-3425 2950);
DISPLAY 0.872340 (-3425 2950);
PAINT GREEN (-3425 2950);
DISPLAY INVISIBLE (-3425 2950);
FORCEPROP 1 LAST HDL_TAP TRUE
J 0
(-3100 2775);
DISPLAY 0.872340 (-3100 2775);
DISPLAY INVISIBLE (-3100 2775);
FORCEPROP 1 LAST PATH I227
J 0
(-3427 2900);
DISPLAY 0.872340 (-3427 2900);
PAINT GREEN (-3427 2900);
DISPLAY INVISIBLE (-3427 2900);
FORCEADD TAP..1
(-3425 2850);
FORCEPROP 3 LASTPIN (-3475 2850) SIG_NAME M_G_CPU0_SB_DQ<25>
J 0
(-3465 2860);
DISPLAY 0.659574 (-3465 2860);
PAINT MONO (-3465 2860);
DISPLAY INVISIBLE (-3465 2860);
FORCEPROP 1 LASTPIN (-3475 2850) BN 25
J 0
(-3487 2858);
DISPLAY 0.489362 (-3487 2858);
PAINT GREEN (-3487 2858);
FORCEPROP 2 LAST CDS_LIB mstr_standard
J 0
(-3425 2850);
DISPLAY 0.723404 (-3425 2850);
PAINT MONO (-3425 2850);
DISPLAY INVISIBLE (-3425 2850);
FORCEPROP 1 LAST BODY_TYPE PLUMBING
J 0
(-3425 2900);
DISPLAY 0.872340 (-3425 2900);
PAINT GREEN (-3425 2900);
DISPLAY INVISIBLE (-3425 2900);
FORCEPROP 1 LAST HDL_TAP TRUE
J 0
(-3100 2725);
DISPLAY 0.872340 (-3100 2725);
DISPLAY INVISIBLE (-3100 2725);
FORCEPROP 1 LAST PATH I228
J 0
(-3427 2850);
DISPLAY 0.872340 (-3427 2850);
PAINT GREEN (-3427 2850);
DISPLAY INVISIBLE (-3427 2850);
FORCEADD TAP..1
(-3425 2800);
FORCEPROP 3 LASTPIN (-3475 2800) SIG_NAME M_G_CPU0_SB_DQ<26>
J 0
(-3465 2810);
DISPLAY 0.659574 (-3465 2810);
PAINT MONO (-3465 2810);
DISPLAY INVISIBLE (-3465 2810);
FORCEPROP 1 LASTPIN (-3475 2800) BN 26
J 0
(-3487 2808);
DISPLAY 0.489362 (-3487 2808);
PAINT GREEN (-3487 2808);
FORCEPROP 2 LAST CDS_LIB mstr_standard
J 0
(-3425 2800);
DISPLAY 0.723404 (-3425 2800);
PAINT MONO (-3425 2800);
DISPLAY INVISIBLE (-3425 2800);
FORCEPROP 1 LAST BODY_TYPE PLUMBING
J 0
(-3425 2850);
DISPLAY 0.872340 (-3425 2850);
PAINT GREEN (-3425 2850);
DISPLAY INVISIBLE (-3425 2850);
FORCEPROP 1 LAST HDL_TAP TRUE
J 0
(-3100 2675);
DISPLAY 0.872340 (-3100 2675);
DISPLAY INVISIBLE (-3100 2675);
FORCEPROP 1 LAST PATH I229
J 0
(-3427 2800);
DISPLAY 0.872340 (-3427 2800);
PAINT GREEN (-3427 2800);
DISPLAY INVISIBLE (-3427 2800);
FORCEADD TAP..1
(-3425 2750);
FORCEPROP 3 LASTPIN (-3475 2750) SIG_NAME M_G_CPU0_SB_DQ<27>
J 0
(-3465 2760);
DISPLAY 0.659574 (-3465 2760);
PAINT MONO (-3465 2760);
DISPLAY INVISIBLE (-3465 2760);
FORCEPROP 1 LASTPIN (-3475 2750) BN 27
J 0
(-3487 2758);
DISPLAY 0.489362 (-3487 2758);
PAINT GREEN (-3487 2758);
FORCEPROP 2 LAST CDS_LIB mstr_standard
J 0
(-3425 2750);
DISPLAY 0.723404 (-3425 2750);
PAINT MONO (-3425 2750);
DISPLAY INVISIBLE (-3425 2750);
FORCEPROP 1 LAST BODY_TYPE PLUMBING
J 0
(-3425 2800);
DISPLAY 0.872340 (-3425 2800);
PAINT GREEN (-3425 2800);
DISPLAY INVISIBLE (-3425 2800);
FORCEPROP 1 LAST HDL_TAP TRUE
J 0
(-3100 2625);
DISPLAY 0.872340 (-3100 2625);
DISPLAY INVISIBLE (-3100 2625);
FORCEPROP 1 LAST PATH I230
J 0
(-3427 2750);
DISPLAY 0.872340 (-3427 2750);
PAINT GREEN (-3427 2750);
DISPLAY INVISIBLE (-3427 2750);
FORCEADD TAP..1
(-3425 2700);
FORCEPROP 3 LASTPIN (-3475 2700) SIG_NAME M_G_CPU0_SB_DQ<28>
J 0
(-3465 2710);
DISPLAY 0.659574 (-3465 2710);
PAINT MONO (-3465 2710);
DISPLAY INVISIBLE (-3465 2710);
FORCEPROP 1 LASTPIN (-3475 2700) BN 28
J 0
(-3487 2708);
DISPLAY 0.489362 (-3487 2708);
PAINT GREEN (-3487 2708);
FORCEPROP 2 LAST CDS_LIB mstr_standard
J 0
(-3425 2700);
DISPLAY 0.723404 (-3425 2700);
PAINT MONO (-3425 2700);
DISPLAY INVISIBLE (-3425 2700);
FORCEPROP 1 LAST BODY_TYPE PLUMBING
J 0
(-3425 2750);
DISPLAY 0.872340 (-3425 2750);
PAINT GREEN (-3425 2750);
DISPLAY INVISIBLE (-3425 2750);
FORCEPROP 1 LAST HDL_TAP TRUE
J 0
(-3100 2575);
DISPLAY 0.872340 (-3100 2575);
DISPLAY INVISIBLE (-3100 2575);
FORCEPROP 1 LAST PATH I231
J 0
(-3427 2700);
DISPLAY 0.872340 (-3427 2700);
PAINT GREEN (-3427 2700);
DISPLAY INVISIBLE (-3427 2700);
FORCEADD TAP..1
(-3425 2650);
FORCEPROP 3 LASTPIN (-3475 2650) SIG_NAME M_G_CPU0_SB_DQ<29>
J 0
(-3465 2660);
DISPLAY 0.659574 (-3465 2660);
PAINT MONO (-3465 2660);
DISPLAY INVISIBLE (-3465 2660);
FORCEPROP 1 LASTPIN (-3475 2650) BN 29
J 0
(-3487 2658);
DISPLAY 0.489362 (-3487 2658);
PAINT GREEN (-3487 2658);
FORCEPROP 2 LAST CDS_LIB mstr_standard
J 0
(-3425 2650);
DISPLAY 0.723404 (-3425 2650);
PAINT MONO (-3425 2650);
DISPLAY INVISIBLE (-3425 2650);
FORCEPROP 1 LAST BODY_TYPE PLUMBING
J 0
(-3425 2700);
DISPLAY 0.872340 (-3425 2700);
PAINT GREEN (-3425 2700);
DISPLAY INVISIBLE (-3425 2700);
FORCEPROP 1 LAST HDL_TAP TRUE
J 0
(-3100 2525);
DISPLAY 0.872340 (-3100 2525);
DISPLAY INVISIBLE (-3100 2525);
FORCEPROP 1 LAST PATH I232
J 0
(-3427 2650);
DISPLAY 0.872340 (-3427 2650);
PAINT GREEN (-3427 2650);
DISPLAY INVISIBLE (-3427 2650);
FORCEADD TAP..1
(-3425 2600);
FORCEPROP 3 LASTPIN (-3475 2600) SIG_NAME M_G_CPU0_SB_DQ<30>
J 0
(-3465 2610);
DISPLAY 0.659574 (-3465 2610);
PAINT MONO (-3465 2610);
DISPLAY INVISIBLE (-3465 2610);
FORCEPROP 1 LASTPIN (-3475 2600) BN 30
J 0
(-3487 2608);
DISPLAY 0.489362 (-3487 2608);
PAINT GREEN (-3487 2608);
FORCEPROP 2 LAST CDS_LIB mstr_standard
J 0
(-3425 2600);
DISPLAY 0.723404 (-3425 2600);
PAINT MONO (-3425 2600);
DISPLAY INVISIBLE (-3425 2600);
FORCEPROP 1 LAST BODY_TYPE PLUMBING
J 0
(-3425 2650);
DISPLAY 0.872340 (-3425 2650);
PAINT GREEN (-3425 2650);
DISPLAY INVISIBLE (-3425 2650);
FORCEPROP 1 LAST HDL_TAP TRUE
J 0
(-3100 2475);
DISPLAY 0.872340 (-3100 2475);
DISPLAY INVISIBLE (-3100 2475);
FORCEPROP 1 LAST PATH I233
J 0
(-3427 2600);
DISPLAY 0.872340 (-3427 2600);
PAINT GREEN (-3427 2600);
DISPLAY INVISIBLE (-3427 2600);
FORCEADD TAP..1
(-3425 2450);
FORCEPROP 3 LASTPIN (-3475 2450) SIG_NAME M_G_CPU0_SA_CB<0>
J 0
(-3465 2460);
DISPLAY 0.659574 (-3465 2460);
PAINT MONO (-3465 2460);
DISPLAY INVISIBLE (-3465 2460);
FORCEPROP 1 LASTPIN (-3475 2450) BN 0
J 0
(-3487 2458);
DISPLAY 0.489362 (-3487 2458);
PAINT GREEN (-3487 2458);
FORCEPROP 2 LAST CDS_LIB mstr_standard
J 2
(-3425 2450);
DISPLAY 0.723404 (-3425 2450);
PAINT MONO (-3425 2450);
DISPLAY INVISIBLE (-3425 2450);
FORCEPROP 1 LAST BODY_TYPE PLUMBING
J 0
(-3425 2500);
DISPLAY 0.872340 (-3425 2500);
PAINT GREEN (-3425 2500);
DISPLAY INVISIBLE (-3425 2500);
FORCEPROP 1 LAST HDL_TAP TRUE
J 0
(-3100 2325);
DISPLAY 0.872340 (-3100 2325);
DISPLAY INVISIBLE (-3100 2325);
FORCEPROP 1 LAST PATH I234
J 0
(-3427 2450);
DISPLAY 0.872340 (-3427 2450);
PAINT GREEN (-3427 2450);
DISPLAY INVISIBLE (-3427 2450);
FORCEADD TAP..1
(-3425 2550);
FORCEPROP 3 LASTPIN (-3475 2550) SIG_NAME M_G_CPU0_SB_DQ<31>
J 0
(-3465 2560);
DISPLAY 0.659574 (-3465 2560);
PAINT MONO (-3465 2560);
DISPLAY INVISIBLE (-3465 2560);
FORCEPROP 1 LASTPIN (-3475 2550) BN 31
J 0
(-3487 2558);
DISPLAY 0.489362 (-3487 2558);
PAINT GREEN (-3487 2558);
FORCEPROP 2 LAST CDS_LIB mstr_standard
J 0
(-3425 2550);
DISPLAY 0.723404 (-3425 2550);
PAINT MONO (-3425 2550);
DISPLAY INVISIBLE (-3425 2550);
FORCEPROP 1 LAST BODY_TYPE PLUMBING
J 0
(-3425 2600);
DISPLAY 0.872340 (-3425 2600);
PAINT GREEN (-3425 2600);
DISPLAY INVISIBLE (-3425 2600);
FORCEPROP 1 LAST HDL_TAP TRUE
J 0
(-3100 2425);
DISPLAY 0.872340 (-3100 2425);
DISPLAY INVISIBLE (-3100 2425);
FORCEPROP 1 LAST PATH I235
J 0
(-3427 2550);
DISPLAY 0.872340 (-3427 2550);
PAINT GREEN (-3427 2550);
DISPLAY INVISIBLE (-3427 2550);
FORCEADD TAP..1
(-3425 2400);
FORCEPROP 3 LASTPIN (-3475 2400) SIG_NAME M_G_CPU0_SA_CB<1>
J 0
(-3465 2410);
DISPLAY 0.659574 (-3465 2410);
PAINT MONO (-3465 2410);
DISPLAY INVISIBLE (-3465 2410);
FORCEPROP 1 LASTPIN (-3475 2400) BN 1
J 0
(-3487 2408);
DISPLAY 0.489362 (-3487 2408);
PAINT GREEN (-3487 2408);
FORCEPROP 2 LAST CDS_LIB mstr_standard
J 2
(-3425 2400);
DISPLAY 0.723404 (-3425 2400);
PAINT MONO (-3425 2400);
DISPLAY INVISIBLE (-3425 2400);
FORCEPROP 1 LAST BODY_TYPE PLUMBING
J 0
(-3425 2450);
DISPLAY 0.872340 (-3425 2450);
PAINT GREEN (-3425 2450);
DISPLAY INVISIBLE (-3425 2450);
FORCEPROP 1 LAST HDL_TAP TRUE
J 0
(-3100 2275);
DISPLAY 0.872340 (-3100 2275);
DISPLAY INVISIBLE (-3100 2275);
FORCEPROP 1 LAST PATH I236
J 0
(-3427 2400);
DISPLAY 0.872340 (-3427 2400);
PAINT GREEN (-3427 2400);
DISPLAY INVISIBLE (-3427 2400);
FORCEADD TAP..1
(-3425 2350);
FORCEPROP 3 LASTPIN (-3475 2350) SIG_NAME M_G_CPU0_SA_CB<2>
J 0
(-3465 2360);
DISPLAY 0.659574 (-3465 2360);
PAINT MONO (-3465 2360);
DISPLAY INVISIBLE (-3465 2360);
FORCEPROP 1 LASTPIN (-3475 2350) BN 2
J 0
(-3487 2358);
DISPLAY 0.489362 (-3487 2358);
PAINT GREEN (-3487 2358);
FORCEPROP 2 LAST CDS_LIB mstr_standard
J 2
(-3425 2350);
DISPLAY 0.723404 (-3425 2350);
PAINT MONO (-3425 2350);
DISPLAY INVISIBLE (-3425 2350);
FORCEPROP 1 LAST BODY_TYPE PLUMBING
J 0
(-3425 2400);
DISPLAY 0.872340 (-3425 2400);
PAINT GREEN (-3425 2400);
DISPLAY INVISIBLE (-3425 2400);
FORCEPROP 1 LAST HDL_TAP TRUE
J 0
(-3100 2225);
DISPLAY 0.872340 (-3100 2225);
DISPLAY INVISIBLE (-3100 2225);
FORCEPROP 1 LAST PATH I237
J 0
(-3427 2350);
DISPLAY 0.872340 (-3427 2350);
PAINT GREEN (-3427 2350);
DISPLAY INVISIBLE (-3427 2350);
FORCEADD TAP..1
(-3425 2250);
FORCEPROP 3 LASTPIN (-3475 2250) SIG_NAME M_G_CPU0_SA_CB<4>
J 0
(-3465 2260);
DISPLAY 0.659574 (-3465 2260);
PAINT MONO (-3465 2260);
DISPLAY INVISIBLE (-3465 2260);
FORCEPROP 1 LASTPIN (-3475 2250) BN 4
J 0
(-3487 2258);
DISPLAY 0.489362 (-3487 2258);
PAINT GREEN (-3487 2258);
FORCEPROP 2 LAST CDS_LIB mstr_standard
J 2
(-3425 2250);
DISPLAY 0.723404 (-3425 2250);
PAINT MONO (-3425 2250);
DISPLAY INVISIBLE (-3425 2250);
FORCEPROP 1 LAST BODY_TYPE PLUMBING
J 0
(-3425 2300);
DISPLAY 0.872340 (-3425 2300);
PAINT GREEN (-3425 2300);
DISPLAY INVISIBLE (-3425 2300);
FORCEPROP 1 LAST HDL_TAP TRUE
J 0
(-3100 2125);
DISPLAY 0.872340 (-3100 2125);
DISPLAY INVISIBLE (-3100 2125);
FORCEPROP 1 LAST PATH I238
J 0
(-3427 2250);
DISPLAY 0.872340 (-3427 2250);
PAINT GREEN (-3427 2250);
DISPLAY INVISIBLE (-3427 2250);
FORCEADD TAP..1
(-3425 2300);
FORCEPROP 3 LASTPIN (-3475 2300) SIG_NAME M_G_CPU0_SA_CB<3>
J 0
(-3465 2310);
DISPLAY 0.659574 (-3465 2310);
PAINT MONO (-3465 2310);
DISPLAY INVISIBLE (-3465 2310);
FORCEPROP 1 LASTPIN (-3475 2300) BN 3
J 0
(-3487 2308);
DISPLAY 0.489362 (-3487 2308);
PAINT GREEN (-3487 2308);
FORCEPROP 2 LAST CDS_LIB mstr_standard
J 2
(-3425 2300);
DISPLAY 0.723404 (-3425 2300);
PAINT MONO (-3425 2300);
DISPLAY INVISIBLE (-3425 2300);
FORCEPROP 1 LAST BODY_TYPE PLUMBING
J 0
(-3425 2350);
DISPLAY 0.872340 (-3425 2350);
PAINT GREEN (-3425 2350);
DISPLAY INVISIBLE (-3425 2350);
FORCEPROP 1 LAST HDL_TAP TRUE
J 0
(-3100 2175);
DISPLAY 0.872340 (-3100 2175);
DISPLAY INVISIBLE (-3100 2175);
FORCEPROP 1 LAST PATH I239
J 0
(-3427 2300);
DISPLAY 0.872340 (-3427 2300);
PAINT GREEN (-3427 2300);
DISPLAY INVISIBLE (-3427 2300);
FORCEADD TAP..1
(-3425 2200);
FORCEPROP 3 LASTPIN (-3475 2200) SIG_NAME M_G_CPU0_SA_CB<5>
J 0
(-3465 2210);
DISPLAY 0.659574 (-3465 2210);
PAINT MONO (-3465 2210);
DISPLAY INVISIBLE (-3465 2210);
FORCEPROP 1 LASTPIN (-3475 2200) BN 5
J 0
(-3487 2208);
DISPLAY 0.489362 (-3487 2208);
PAINT GREEN (-3487 2208);
FORCEPROP 2 LAST CDS_LIB mstr_standard
J 2
(-3425 2200);
DISPLAY 0.723404 (-3425 2200);
PAINT MONO (-3425 2200);
DISPLAY INVISIBLE (-3425 2200);
FORCEPROP 1 LAST BODY_TYPE PLUMBING
J 0
(-3425 2250);
DISPLAY 0.872340 (-3425 2250);
PAINT GREEN (-3425 2250);
DISPLAY INVISIBLE (-3425 2250);
FORCEPROP 1 LAST HDL_TAP TRUE
J 0
(-3100 2075);
DISPLAY 0.872340 (-3100 2075);
DISPLAY INVISIBLE (-3100 2075);
FORCEPROP 1 LAST PATH I240
J 0
(-3427 2200);
DISPLAY 0.872340 (-3427 2200);
PAINT GREEN (-3427 2200);
DISPLAY INVISIBLE (-3427 2200);
FORCEADD TAP..1
(-3425 2100);
FORCEPROP 3 LASTPIN (-3475 2100) SIG_NAME M_G_CPU0_SA_CB<7>
J 0
(-3465 2110);
DISPLAY 0.659574 (-3465 2110);
PAINT MONO (-3465 2110);
DISPLAY INVISIBLE (-3465 2110);
FORCEPROP 1 LASTPIN (-3475 2100) BN 7
J 0
(-3487 2108);
DISPLAY 0.489362 (-3487 2108);
PAINT GREEN (-3487 2108);
FORCEPROP 2 LAST CDS_LIB mstr_standard
J 2
(-3425 2100);
DISPLAY 0.723404 (-3425 2100);
PAINT MONO (-3425 2100);
DISPLAY INVISIBLE (-3425 2100);
FORCEPROP 1 LAST BODY_TYPE PLUMBING
J 0
(-3425 2150);
DISPLAY 0.872340 (-3425 2150);
PAINT GREEN (-3425 2150);
DISPLAY INVISIBLE (-3425 2150);
FORCEPROP 1 LAST HDL_TAP TRUE
J 0
(-3100 1975);
DISPLAY 0.872340 (-3100 1975);
DISPLAY INVISIBLE (-3100 1975);
FORCEPROP 1 LAST PATH I241
J 0
(-3427 2100);
DISPLAY 0.872340 (-3427 2100);
PAINT GREEN (-3427 2100);
DISPLAY INVISIBLE (-3427 2100);
FORCEADD TAP..1
(-3425 2150);
FORCEPROP 3 LASTPIN (-3475 2150) SIG_NAME M_G_CPU0_SA_CB<6>
J 0
(-3465 2160);
DISPLAY 0.659574 (-3465 2160);
PAINT MONO (-3465 2160);
DISPLAY INVISIBLE (-3465 2160);
FORCEPROP 1 LASTPIN (-3475 2150) BN 6
J 0
(-3487 2158);
DISPLAY 0.489362 (-3487 2158);
PAINT GREEN (-3487 2158);
FORCEPROP 2 LAST CDS_LIB mstr_standard
J 2
(-3425 2150);
DISPLAY 0.723404 (-3425 2150);
PAINT MONO (-3425 2150);
DISPLAY INVISIBLE (-3425 2150);
FORCEPROP 1 LAST BODY_TYPE PLUMBING
J 0
(-3425 2200);
DISPLAY 0.872340 (-3425 2200);
PAINT GREEN (-3425 2200);
DISPLAY INVISIBLE (-3425 2200);
FORCEPROP 1 LAST HDL_TAP TRUE
J 0
(-3100 2025);
DISPLAY 0.872340 (-3100 2025);
DISPLAY INVISIBLE (-3100 2025);
FORCEPROP 1 LAST PATH I242
J 0
(-3427 2150);
DISPLAY 0.872340 (-3427 2150);
PAINT GREEN (-3427 2150);
DISPLAY INVISIBLE (-3427 2150);
FORCEADD OFFPAGE..6
R 2
(-2825 2050);
FORCEPROP 2 LAST $XR0 91 
J 0
(-2611 2050);
DISPLAY 0.638298 (-2611 2050);
PAINT MONO (-2611 2050);
FORCEPROP 2 LAST PATH I243
J 0
(-2600 2100);
DISPLAY 1.021277 (-2600 2100);
DISPLAY INVISIBLE (-2600 2100);
FORCEPROP 1 LAST COMMENT_BODY TRUE
J 2
(-2925 1975);
DISPLAY 0.872340 (-2925 1975);
PAINT GREEN (-2925 1975);
DISPLAY INVISIBLE (-2925 1975);
FORCEPROP 1 LAST OFFPAGE TRUE
J 2
(-3150 1925);
DISPLAY 0.872340 (-3150 1925);
PAINT GREEN (-3150 1925);
DISPLAY INVISIBLE (-3150 1925);
FORCEPROP 2 LAST CDS_LIB mstr_standard
J 2
(-2825 2050);
DISPLAY 0.723404 (-2825 2050);
PAINT MONO (-2825 2050);
DISPLAY INVISIBLE (-2825 2050);
FORCEADD TAP..1
(-3425 2000);
FORCEPROP 3 LASTPIN (-3475 2000) SIG_NAME M_G_CPU0_SB_CB<0>
J 0
(-3465 2010);
DISPLAY 0.659574 (-3465 2010);
PAINT MONO (-3465 2010);
DISPLAY INVISIBLE (-3465 2010);
FORCEPROP 1 LASTPIN (-3475 2000) BN 0
J 0
(-3487 2008);
DISPLAY 0.489362 (-3487 2008);
PAINT GREEN (-3487 2008);
FORCEPROP 2 LAST CDS_LIB mstr_standard
J 2
(-3425 2000);
DISPLAY 0.723404 (-3425 2000);
PAINT MONO (-3425 2000);
DISPLAY INVISIBLE (-3425 2000);
FORCEPROP 1 LAST BODY_TYPE PLUMBING
J 0
(-3425 2050);
DISPLAY 0.872340 (-3425 2050);
PAINT GREEN (-3425 2050);
DISPLAY INVISIBLE (-3425 2050);
FORCEPROP 1 LAST HDL_TAP TRUE
J 0
(-3100 1875);
DISPLAY 0.872340 (-3100 1875);
DISPLAY INVISIBLE (-3100 1875);
FORCEPROP 1 LAST PATH I244
J 0
(-3427 2000);
DISPLAY 0.872340 (-3427 2000);
PAINT GREEN (-3427 2000);
DISPLAY INVISIBLE (-3427 2000);
FORCEADD TAP..1
(-3425 1950);
FORCEPROP 3 LASTPIN (-3475 1950) SIG_NAME M_G_CPU0_SB_CB<1>
J 0
(-3465 1960);
DISPLAY 0.659574 (-3465 1960);
PAINT MONO (-3465 1960);
DISPLAY INVISIBLE (-3465 1960);
FORCEPROP 1 LASTPIN (-3475 1950) BN 1
J 0
(-3487 1958);
DISPLAY 0.489362 (-3487 1958);
PAINT GREEN (-3487 1958);
FORCEPROP 2 LAST CDS_LIB mstr_standard
J 2
(-3425 1950);
DISPLAY 0.723404 (-3425 1950);
PAINT MONO (-3425 1950);
DISPLAY INVISIBLE (-3425 1950);
FORCEPROP 1 LAST BODY_TYPE PLUMBING
J 0
(-3425 2000);
DISPLAY 0.872340 (-3425 2000);
PAINT GREEN (-3425 2000);
DISPLAY INVISIBLE (-3425 2000);
FORCEPROP 1 LAST HDL_TAP TRUE
J 0
(-3100 1825);
DISPLAY 0.872340 (-3100 1825);
DISPLAY INVISIBLE (-3100 1825);
FORCEPROP 1 LAST PATH I245
J 0
(-3427 1950);
DISPLAY 0.872340 (-3427 1950);
PAINT GREEN (-3427 1950);
DISPLAY INVISIBLE (-3427 1950);
FORCEADD TAP..1
(-3425 1900);
FORCEPROP 3 LASTPIN (-3475 1900) SIG_NAME M_G_CPU0_SB_CB<2>
J 0
(-3465 1910);
DISPLAY 0.659574 (-3465 1910);
PAINT MONO (-3465 1910);
DISPLAY INVISIBLE (-3465 1910);
FORCEPROP 1 LASTPIN (-3475 1900) BN 2
J 0
(-3487 1908);
DISPLAY 0.489362 (-3487 1908);
PAINT GREEN (-3487 1908);
FORCEPROP 2 LAST CDS_LIB mstr_standard
J 2
(-3425 1900);
DISPLAY 0.723404 (-3425 1900);
PAINT MONO (-3425 1900);
DISPLAY INVISIBLE (-3425 1900);
FORCEPROP 1 LAST BODY_TYPE PLUMBING
J 0
(-3425 1950);
DISPLAY 0.872340 (-3425 1950);
PAINT GREEN (-3425 1950);
DISPLAY INVISIBLE (-3425 1950);
FORCEPROP 1 LAST HDL_TAP TRUE
J 0
(-3100 1775);
DISPLAY 0.872340 (-3100 1775);
DISPLAY INVISIBLE (-3100 1775);
FORCEPROP 1 LAST PATH I246
J 0
(-3427 1900);
DISPLAY 0.872340 (-3427 1900);
PAINT GREEN (-3427 1900);
DISPLAY INVISIBLE (-3427 1900);
FORCEADD TAP..1
(-3425 1850);
FORCEPROP 3 LASTPIN (-3475 1850) SIG_NAME M_G_CPU0_SB_CB<3>
J 0
(-3465 1860);
DISPLAY 0.659574 (-3465 1860);
PAINT MONO (-3465 1860);
DISPLAY INVISIBLE (-3465 1860);
FORCEPROP 1 LASTPIN (-3475 1850) BN 3
J 0
(-3487 1858);
DISPLAY 0.489362 (-3487 1858);
PAINT GREEN (-3487 1858);
FORCEPROP 2 LAST CDS_LIB mstr_standard
J 2
(-3425 1850);
DISPLAY 0.723404 (-3425 1850);
PAINT MONO (-3425 1850);
DISPLAY INVISIBLE (-3425 1850);
FORCEPROP 1 LAST BODY_TYPE PLUMBING
J 0
(-3425 1900);
DISPLAY 0.872340 (-3425 1900);
PAINT GREEN (-3425 1900);
DISPLAY INVISIBLE (-3425 1900);
FORCEPROP 1 LAST HDL_TAP TRUE
J 0
(-3100 1725);
DISPLAY 0.872340 (-3100 1725);
DISPLAY INVISIBLE (-3100 1725);
FORCEPROP 1 LAST PATH I247
J 0
(-3427 1850);
DISPLAY 0.872340 (-3427 1850);
PAINT GREEN (-3427 1850);
DISPLAY INVISIBLE (-3427 1850);
FORCEADD TAP..1
(-3425 1800);
FORCEPROP 3 LASTPIN (-3475 1800) SIG_NAME M_G_CPU0_SB_CB<4>
J 0
(-3465 1810);
DISPLAY 0.659574 (-3465 1810);
PAINT MONO (-3465 1810);
DISPLAY INVISIBLE (-3465 1810);
FORCEPROP 1 LASTPIN (-3475 1800) BN 4
J 0
(-3487 1808);
DISPLAY 0.489362 (-3487 1808);
PAINT GREEN (-3487 1808);
FORCEPROP 2 LAST CDS_LIB mstr_standard
J 2
(-3425 1800);
DISPLAY 0.723404 (-3425 1800);
PAINT MONO (-3425 1800);
DISPLAY INVISIBLE (-3425 1800);
FORCEPROP 1 LAST BODY_TYPE PLUMBING
J 0
(-3425 1850);
DISPLAY 0.872340 (-3425 1850);
PAINT GREEN (-3425 1850);
DISPLAY INVISIBLE (-3425 1850);
FORCEPROP 1 LAST HDL_TAP TRUE
J 0
(-3100 1675);
DISPLAY 0.872340 (-3100 1675);
DISPLAY INVISIBLE (-3100 1675);
FORCEPROP 1 LAST PATH I248
J 0
(-3427 1800);
DISPLAY 0.872340 (-3427 1800);
PAINT GREEN (-3427 1800);
DISPLAY INVISIBLE (-3427 1800);
FORCEADD TAP..1
(-3425 1750);
FORCEPROP 3 LASTPIN (-3475 1750) SIG_NAME M_G_CPU0_SB_CB<5>
J 0
(-3465 1760);
DISPLAY 0.659574 (-3465 1760);
PAINT MONO (-3465 1760);
DISPLAY INVISIBLE (-3465 1760);
FORCEPROP 1 LASTPIN (-3475 1750) BN 5
J 0
(-3487 1758);
DISPLAY 0.489362 (-3487 1758);
PAINT GREEN (-3487 1758);
FORCEPROP 2 LAST CDS_LIB mstr_standard
J 2
(-3425 1750);
DISPLAY 0.723404 (-3425 1750);
PAINT MONO (-3425 1750);
DISPLAY INVISIBLE (-3425 1750);
FORCEPROP 1 LAST BODY_TYPE PLUMBING
J 0
(-3425 1800);
DISPLAY 0.872340 (-3425 1800);
PAINT GREEN (-3425 1800);
DISPLAY INVISIBLE (-3425 1800);
FORCEPROP 1 LAST HDL_TAP TRUE
J 0
(-3100 1625);
DISPLAY 0.872340 (-3100 1625);
DISPLAY INVISIBLE (-3100 1625);
FORCEPROP 1 LAST PATH I249
J 0
(-3427 1750);
DISPLAY 0.872340 (-3427 1750);
PAINT GREEN (-3427 1750);
DISPLAY INVISIBLE (-3427 1750);
FORCEADD TAP..1
(-3425 1700);
FORCEPROP 3 LASTPIN (-3475 1700) SIG_NAME M_G_CPU0_SB_CB<6>
J 0
(-3465 1710);
DISPLAY 0.659574 (-3465 1710);
PAINT MONO (-3465 1710);
DISPLAY INVISIBLE (-3465 1710);
FORCEPROP 1 LASTPIN (-3475 1700) BN 6
J 0
(-3487 1708);
DISPLAY 0.489362 (-3487 1708);
PAINT GREEN (-3487 1708);
FORCEPROP 2 LAST CDS_LIB mstr_standard
J 2
(-3425 1700);
DISPLAY 0.723404 (-3425 1700);
PAINT MONO (-3425 1700);
DISPLAY INVISIBLE (-3425 1700);
FORCEPROP 1 LAST BODY_TYPE PLUMBING
J 0
(-3425 1750);
DISPLAY 0.872340 (-3425 1750);
PAINT GREEN (-3425 1750);
DISPLAY INVISIBLE (-3425 1750);
FORCEPROP 1 LAST HDL_TAP TRUE
J 0
(-3100 1575);
DISPLAY 0.872340 (-3100 1575);
DISPLAY INVISIBLE (-3100 1575);
FORCEPROP 1 LAST PATH I250
J 0
(-3427 1700);
DISPLAY 0.872340 (-3427 1700);
PAINT GREEN (-3427 1700);
DISPLAY INVISIBLE (-3427 1700);
FORCEADD TAP..1
(-3425 1650);
FORCEPROP 3 LASTPIN (-3475 1650) SIG_NAME M_G_CPU0_SB_CB<7>
J 0
(-3465 1660);
DISPLAY 0.659574 (-3465 1660);
PAINT MONO (-3465 1660);
DISPLAY INVISIBLE (-3465 1660);
FORCEPROP 1 LASTPIN (-3475 1650) BN 7
J 0
(-3487 1658);
DISPLAY 0.489362 (-3487 1658);
PAINT GREEN (-3487 1658);
FORCEPROP 2 LAST CDS_LIB mstr_standard
J 2
(-3425 1650);
DISPLAY 0.723404 (-3425 1650);
PAINT MONO (-3425 1650);
DISPLAY INVISIBLE (-3425 1650);
FORCEPROP 1 LAST BODY_TYPE PLUMBING
J 0
(-3425 1700);
DISPLAY 0.872340 (-3425 1700);
PAINT GREEN (-3425 1700);
DISPLAY INVISIBLE (-3425 1700);
FORCEPROP 1 LAST HDL_TAP TRUE
J 0
(-3100 1525);
DISPLAY 0.872340 (-3100 1525);
DISPLAY INVISIBLE (-3100 1525);
FORCEPROP 1 LAST PATH I251
J 0
(-3427 1650);
DISPLAY 0.872340 (-3427 1650);
PAINT GREEN (-3427 1650);
DISPLAY INVISIBLE (-3427 1650);
FORCEADD TAP..1
R 2
(-5850 6050);
FORCEPROP 3 LASTPIN (-5800 6050) SIG_NAME M_G_CPU0_SA_DQS_DP<0>
J 0
(-5790 6060);
DISPLAY 0.659574 (-5790 6060);
PAINT MONO (-5790 6060);
DISPLAY INVISIBLE (-5790 6060);
FORCEPROP 1 LASTPIN (-5800 6050) BN 0
J 2
(-5788 6058);
DISPLAY 0.489362 (-5788 6058);
PAINT GREEN (-5788 6058);
FORCEPROP 2 LAST CDS_LIB mstr_standard
J 2
(-5850 6050);
DISPLAY 0.723404 (-5850 6050);
PAINT MONO (-5850 6050);
DISPLAY INVISIBLE (-5850 6050);
FORCEPROP 1 LAST BODY_TYPE PLUMBING
J 2
(-5850 6100);
DISPLAY 0.872340 (-5850 6100);
PAINT GREEN (-5850 6100);
DISPLAY INVISIBLE (-5850 6100);
FORCEPROP 1 LAST HDL_TAP TRUE
J 2
(-6175 5925);
DISPLAY 0.872340 (-6175 5925);
DISPLAY INVISIBLE (-6175 5925);
FORCEPROP 1 LAST PATH I252
J 2
(-5848 6050);
DISPLAY 0.872340 (-5848 6050);
PAINT GREEN (-5848 6050);
DISPLAY INVISIBLE (-5848 6050);
FORCEADD TAP..1
R 2
(-5850 5950);
FORCEPROP 3 LASTPIN (-5800 5950) SIG_NAME M_G_CPU0_SA_DQS_DP<1>
J 0
(-5790 5960);
DISPLAY 0.659574 (-5790 5960);
PAINT MONO (-5790 5960);
DISPLAY INVISIBLE (-5790 5960);
FORCEPROP 1 LASTPIN (-5800 5950) BN 1
J 2
(-5788 5958);
DISPLAY 0.489362 (-5788 5958);
PAINT GREEN (-5788 5958);
FORCEPROP 2 LAST CDS_LIB mstr_standard
J 2
(-5850 5950);
DISPLAY 0.723404 (-5850 5950);
PAINT MONO (-5850 5950);
DISPLAY INVISIBLE (-5850 5950);
FORCEPROP 1 LAST BODY_TYPE PLUMBING
J 2
(-5850 6000);
DISPLAY 0.872340 (-5850 6000);
PAINT GREEN (-5850 6000);
DISPLAY INVISIBLE (-5850 6000);
FORCEPROP 1 LAST HDL_TAP TRUE
J 2
(-6175 5825);
DISPLAY 0.872340 (-6175 5825);
DISPLAY INVISIBLE (-6175 5825);
FORCEPROP 1 LAST PATH I253
J 2
(-5848 5950);
DISPLAY 0.872340 (-5848 5950);
PAINT GREEN (-5848 5950);
DISPLAY INVISIBLE (-5848 5950);
FORCEADD TAP..1
R 2
(-5850 5850);
FORCEPROP 3 LASTPIN (-5800 5850) SIG_NAME M_G_CPU0_SA_DQS_DP<2>
J 0
(-5790 5860);
DISPLAY 0.659574 (-5790 5860);
PAINT MONO (-5790 5860);
DISPLAY INVISIBLE (-5790 5860);
FORCEPROP 1 LASTPIN (-5800 5850) BN 2
J 2
(-5788 5858);
DISPLAY 0.489362 (-5788 5858);
PAINT GREEN (-5788 5858);
FORCEPROP 2 LAST CDS_LIB mstr_standard
J 2
(-5850 5850);
DISPLAY 0.723404 (-5850 5850);
PAINT MONO (-5850 5850);
DISPLAY INVISIBLE (-5850 5850);
FORCEPROP 1 LAST BODY_TYPE PLUMBING
J 2
(-5850 5900);
DISPLAY 0.872340 (-5850 5900);
PAINT GREEN (-5850 5900);
DISPLAY INVISIBLE (-5850 5900);
FORCEPROP 1 LAST HDL_TAP TRUE
J 2
(-6175 5725);
DISPLAY 0.872340 (-6175 5725);
DISPLAY INVISIBLE (-6175 5725);
FORCEPROP 1 LAST PATH I254
J 2
(-5848 5850);
DISPLAY 0.872340 (-5848 5850);
PAINT GREEN (-5848 5850);
DISPLAY INVISIBLE (-5848 5850);
FORCEADD TAP..1
R 2
(-5850 5750);
FORCEPROP 3 LASTPIN (-5800 5750) SIG_NAME M_G_CPU0_SA_DQS_DP<3>
J 0
(-5790 5760);
DISPLAY 0.659574 (-5790 5760);
PAINT MONO (-5790 5760);
DISPLAY INVISIBLE (-5790 5760);
FORCEPROP 1 LASTPIN (-5800 5750) BN 3
J 2
(-5788 5758);
DISPLAY 0.489362 (-5788 5758);
PAINT GREEN (-5788 5758);
FORCEPROP 2 LAST CDS_LIB mstr_standard
J 2
(-5850 5750);
DISPLAY 0.723404 (-5850 5750);
PAINT MONO (-5850 5750);
DISPLAY INVISIBLE (-5850 5750);
FORCEPROP 1 LAST BODY_TYPE PLUMBING
J 2
(-5850 5800);
DISPLAY 0.872340 (-5850 5800);
PAINT GREEN (-5850 5800);
DISPLAY INVISIBLE (-5850 5800);
FORCEPROP 1 LAST HDL_TAP TRUE
J 2
(-6175 5625);
DISPLAY 0.872340 (-6175 5625);
DISPLAY INVISIBLE (-6175 5625);
FORCEPROP 1 LAST PATH I255
J 2
(-5848 5750);
DISPLAY 0.872340 (-5848 5750);
PAINT GREEN (-5848 5750);
DISPLAY INVISIBLE (-5848 5750);
FORCEADD TAP..1
R 2
(-5850 5650);
FORCEPROP 3 LASTPIN (-5800 5650) SIG_NAME M_G_CPU0_SA_DQS_DP<4>
J 0
(-5790 5660);
DISPLAY 0.659574 (-5790 5660);
PAINT MONO (-5790 5660);
DISPLAY INVISIBLE (-5790 5660);
FORCEPROP 1 LASTPIN (-5800 5650) BN 4
J 2
(-5788 5658);
DISPLAY 0.489362 (-5788 5658);
PAINT GREEN (-5788 5658);
FORCEPROP 2 LAST CDS_LIB mstr_standard
J 2
(-5850 5650);
DISPLAY 0.723404 (-5850 5650);
PAINT MONO (-5850 5650);
DISPLAY INVISIBLE (-5850 5650);
FORCEPROP 1 LAST BODY_TYPE PLUMBING
J 2
(-5850 5700);
DISPLAY 0.872340 (-5850 5700);
PAINT GREEN (-5850 5700);
DISPLAY INVISIBLE (-5850 5700);
FORCEPROP 1 LAST HDL_TAP TRUE
J 2
(-6175 5525);
DISPLAY 0.872340 (-6175 5525);
DISPLAY INVISIBLE (-6175 5525);
FORCEPROP 1 LAST PATH I256
J 2
(-5848 5650);
DISPLAY 0.872340 (-5848 5650);
PAINT GREEN (-5848 5650);
DISPLAY INVISIBLE (-5848 5650);
FORCEADD TAP..1
R 2
(-6050 6000);
FORCEPROP 3 LASTPIN (-6000 6000) SIG_NAME M_G_CPU0_SA_DQS_DN<0>
J 0
(-5990 6010);
DISPLAY 0.659574 (-5990 6010);
PAINT MONO (-5990 6010);
DISPLAY INVISIBLE (-5990 6010);
FORCEPROP 1 LASTPIN (-6000 6000) BN 0
J 2
(-5988 6008);
DISPLAY 0.489362 (-5988 6008);
PAINT GREEN (-5988 6008);
FORCEPROP 2 LAST CDS_LIB mstr_standard
J 2
(-6050 6000);
DISPLAY 0.723404 (-6050 6000);
PAINT MONO (-6050 6000);
DISPLAY INVISIBLE (-6050 6000);
FORCEPROP 1 LAST BODY_TYPE PLUMBING
J 2
(-6050 6050);
DISPLAY 0.872340 (-6050 6050);
PAINT GREEN (-6050 6050);
DISPLAY INVISIBLE (-6050 6050);
FORCEPROP 1 LAST HDL_TAP TRUE
J 2
(-6375 5875);
DISPLAY 0.872340 (-6375 5875);
DISPLAY INVISIBLE (-6375 5875);
FORCEPROP 1 LAST PATH I257
J 2
(-6048 6000);
DISPLAY 0.872340 (-6048 6000);
PAINT GREEN (-6048 6000);
DISPLAY INVISIBLE (-6048 6000);
FORCEADD TAP..1
R 2
(-6050 5900);
FORCEPROP 3 LASTPIN (-6000 5900) SIG_NAME M_G_CPU0_SA_DQS_DN<1>
J 0
(-5990 5910);
DISPLAY 0.659574 (-5990 5910);
PAINT MONO (-5990 5910);
DISPLAY INVISIBLE (-5990 5910);
FORCEPROP 1 LASTPIN (-6000 5900) BN 1
J 2
(-5988 5908);
DISPLAY 0.489362 (-5988 5908);
PAINT GREEN (-5988 5908);
FORCEPROP 2 LAST CDS_LIB mstr_standard
J 2
(-6050 5900);
DISPLAY 0.723404 (-6050 5900);
PAINT MONO (-6050 5900);
DISPLAY INVISIBLE (-6050 5900);
FORCEPROP 1 LAST BODY_TYPE PLUMBING
J 2
(-6050 5950);
DISPLAY 0.872340 (-6050 5950);
PAINT GREEN (-6050 5950);
DISPLAY INVISIBLE (-6050 5950);
FORCEPROP 1 LAST HDL_TAP TRUE
J 2
(-6375 5775);
DISPLAY 0.872340 (-6375 5775);
DISPLAY INVISIBLE (-6375 5775);
FORCEPROP 1 LAST PATH I258
J 2
(-6048 5900);
DISPLAY 0.872340 (-6048 5900);
PAINT GREEN (-6048 5900);
DISPLAY INVISIBLE (-6048 5900);
FORCEADD TAP..1
R 2
(-6050 5800);
FORCEPROP 3 LASTPIN (-6000 5800) SIG_NAME M_G_CPU0_SA_DQS_DN<2>
J 0
(-5990 5810);
DISPLAY 0.659574 (-5990 5810);
PAINT MONO (-5990 5810);
DISPLAY INVISIBLE (-5990 5810);
FORCEPROP 1 LASTPIN (-6000 5800) BN 2
J 2
(-5988 5808);
DISPLAY 0.489362 (-5988 5808);
PAINT GREEN (-5988 5808);
FORCEPROP 2 LAST CDS_LIB mstr_standard
J 2
(-6050 5800);
DISPLAY 0.723404 (-6050 5800);
PAINT MONO (-6050 5800);
DISPLAY INVISIBLE (-6050 5800);
FORCEPROP 1 LAST BODY_TYPE PLUMBING
J 2
(-6050 5850);
DISPLAY 0.872340 (-6050 5850);
PAINT GREEN (-6050 5850);
DISPLAY INVISIBLE (-6050 5850);
FORCEPROP 1 LAST HDL_TAP TRUE
J 2
(-6375 5675);
DISPLAY 0.872340 (-6375 5675);
DISPLAY INVISIBLE (-6375 5675);
FORCEPROP 1 LAST PATH I259
J 2
(-6048 5800);
DISPLAY 0.872340 (-6048 5800);
PAINT GREEN (-6048 5800);
DISPLAY INVISIBLE (-6048 5800);
FORCEADD TAP..1
R 2
(-6050 5700);
FORCEPROP 3 LASTPIN (-6000 5700) SIG_NAME M_G_CPU0_SA_DQS_DN<3>
J 0
(-5990 5710);
DISPLAY 0.659574 (-5990 5710);
PAINT MONO (-5990 5710);
DISPLAY INVISIBLE (-5990 5710);
FORCEPROP 1 LASTPIN (-6000 5700) BN 3
J 2
(-5988 5708);
DISPLAY 0.489362 (-5988 5708);
PAINT GREEN (-5988 5708);
FORCEPROP 2 LAST CDS_LIB mstr_standard
J 2
(-6050 5700);
DISPLAY 0.723404 (-6050 5700);
PAINT MONO (-6050 5700);
DISPLAY INVISIBLE (-6050 5700);
FORCEPROP 1 LAST BODY_TYPE PLUMBING
J 2
(-6050 5750);
DISPLAY 0.872340 (-6050 5750);
PAINT GREEN (-6050 5750);
DISPLAY INVISIBLE (-6050 5750);
FORCEPROP 1 LAST HDL_TAP TRUE
J 2
(-6375 5575);
DISPLAY 0.872340 (-6375 5575);
DISPLAY INVISIBLE (-6375 5575);
FORCEPROP 1 LAST PATH I260
J 2
(-6048 5700);
DISPLAY 0.872340 (-6048 5700);
PAINT GREEN (-6048 5700);
DISPLAY INVISIBLE (-6048 5700);
FORCEADD TAP..1
R 2
(-5850 5450);
FORCEPROP 3 LASTPIN (-5800 5450) SIG_NAME M_G_CPU0_SA_DQS_DP<6>
J 0
(-5790 5460);
DISPLAY 0.659574 (-5790 5460);
PAINT MONO (-5790 5460);
DISPLAY INVISIBLE (-5790 5460);
FORCEPROP 1 LASTPIN (-5800 5450) BN 6
J 2
(-5788 5458);
DISPLAY 0.489362 (-5788 5458);
PAINT GREEN (-5788 5458);
FORCEPROP 2 LAST CDS_LIB mstr_standard
J 2
(-5850 5450);
DISPLAY 0.723404 (-5850 5450);
PAINT MONO (-5850 5450);
DISPLAY INVISIBLE (-5850 5450);
FORCEPROP 1 LAST BODY_TYPE PLUMBING
J 2
(-5850 5500);
DISPLAY 0.872340 (-5850 5500);
PAINT GREEN (-5850 5500);
DISPLAY INVISIBLE (-5850 5500);
FORCEPROP 1 LAST HDL_TAP TRUE
J 2
(-6175 5325);
DISPLAY 0.872340 (-6175 5325);
DISPLAY INVISIBLE (-6175 5325);
FORCEPROP 1 LAST PATH I261
J 2
(-5848 5450);
DISPLAY 0.872340 (-5848 5450);
PAINT GREEN (-5848 5450);
DISPLAY INVISIBLE (-5848 5450);
FORCEADD TAP..1
R 2
(-5850 5550);
FORCEPROP 3 LASTPIN (-5800 5550) SIG_NAME M_G_CPU0_SA_DQS_DP<5>
J 0
(-5790 5560);
DISPLAY 0.659574 (-5790 5560);
PAINT MONO (-5790 5560);
DISPLAY INVISIBLE (-5790 5560);
FORCEPROP 1 LASTPIN (-5800 5550) BN 5
J 2
(-5788 5558);
DISPLAY 0.489362 (-5788 5558);
PAINT GREEN (-5788 5558);
FORCEPROP 2 LAST CDS_LIB mstr_standard
J 2
(-5850 5550);
DISPLAY 0.723404 (-5850 5550);
PAINT MONO (-5850 5550);
DISPLAY INVISIBLE (-5850 5550);
FORCEPROP 1 LAST BODY_TYPE PLUMBING
J 2
(-5850 5600);
DISPLAY 0.872340 (-5850 5600);
PAINT GREEN (-5850 5600);
DISPLAY INVISIBLE (-5850 5600);
FORCEPROP 1 LAST HDL_TAP TRUE
J 2
(-6175 5425);
DISPLAY 0.872340 (-6175 5425);
DISPLAY INVISIBLE (-6175 5425);
FORCEPROP 1 LAST PATH I262
J 2
(-5848 5550);
DISPLAY 0.872340 (-5848 5550);
PAINT GREEN (-5848 5550);
DISPLAY INVISIBLE (-5848 5550);
FORCEADD TAP..1
R 2
(-5850 5350);
FORCEPROP 3 LASTPIN (-5800 5350) SIG_NAME M_G_CPU0_SA_DQS_DP<7>
J 0
(-5790 5360);
DISPLAY 0.659574 (-5790 5360);
PAINT MONO (-5790 5360);
DISPLAY INVISIBLE (-5790 5360);
FORCEPROP 1 LASTPIN (-5800 5350) BN 7
J 2
(-5788 5358);
DISPLAY 0.489362 (-5788 5358);
PAINT GREEN (-5788 5358);
FORCEPROP 2 LAST CDS_LIB mstr_standard
J 2
(-5850 5350);
DISPLAY 0.723404 (-5850 5350);
PAINT MONO (-5850 5350);
DISPLAY INVISIBLE (-5850 5350);
FORCEPROP 1 LAST BODY_TYPE PLUMBING
J 2
(-5850 5400);
DISPLAY 0.872340 (-5850 5400);
PAINT GREEN (-5850 5400);
DISPLAY INVISIBLE (-5850 5400);
FORCEPROP 1 LAST HDL_TAP TRUE
J 2
(-6175 5225);
DISPLAY 0.872340 (-6175 5225);
DISPLAY INVISIBLE (-6175 5225);
FORCEPROP 1 LAST PATH I263
J 2
(-5848 5350);
DISPLAY 0.872340 (-5848 5350);
PAINT GREEN (-5848 5350);
DISPLAY INVISIBLE (-5848 5350);
FORCEADD TAP..1
R 2
(-5850 5250);
FORCEPROP 3 LASTPIN (-5800 5250) SIG_NAME M_G_CPU0_SA_DQS_DP<8>
J 0
(-5790 5260);
DISPLAY 0.659574 (-5790 5260);
PAINT MONO (-5790 5260);
DISPLAY INVISIBLE (-5790 5260);
FORCEPROP 1 LASTPIN (-5800 5250) BN 8
J 2
(-5788 5258);
DISPLAY 0.489362 (-5788 5258);
PAINT GREEN (-5788 5258);
FORCEPROP 2 LAST CDS_LIB mstr_standard
J 2
(-5850 5250);
DISPLAY 0.723404 (-5850 5250);
PAINT MONO (-5850 5250);
DISPLAY INVISIBLE (-5850 5250);
FORCEPROP 1 LAST BODY_TYPE PLUMBING
J 2
(-5850 5300);
DISPLAY 0.872340 (-5850 5300);
PAINT GREEN (-5850 5300);
DISPLAY INVISIBLE (-5850 5300);
FORCEPROP 1 LAST HDL_TAP TRUE
J 2
(-6175 5125);
DISPLAY 0.872340 (-6175 5125);
DISPLAY INVISIBLE (-6175 5125);
FORCEPROP 1 LAST PATH I264
J 2
(-5848 5250);
DISPLAY 0.872340 (-5848 5250);
PAINT GREEN (-5848 5250);
DISPLAY INVISIBLE (-5848 5250);
FORCEADD TAP..1
R 2
(-5850 5150);
FORCEPROP 3 LASTPIN (-5800 5150) SIG_NAME M_G_CPU0_SA_DQS_DP<9>
J 0
(-5790 5160);
DISPLAY 0.659574 (-5790 5160);
PAINT MONO (-5790 5160);
DISPLAY INVISIBLE (-5790 5160);
FORCEPROP 1 LASTPIN (-5800 5150) BN 9
J 2
(-5788 5158);
DISPLAY 0.489362 (-5788 5158);
PAINT GREEN (-5788 5158);
FORCEPROP 2 LAST CDS_LIB mstr_standard
J 2
(-5850 5150);
DISPLAY 0.723404 (-5850 5150);
PAINT MONO (-5850 5150);
DISPLAY INVISIBLE (-5850 5150);
FORCEPROP 1 LAST BODY_TYPE PLUMBING
J 2
(-5850 5200);
DISPLAY 0.872340 (-5850 5200);
PAINT GREEN (-5850 5200);
DISPLAY INVISIBLE (-5850 5200);
FORCEPROP 1 LAST HDL_TAP TRUE
J 2
(-6175 5025);
DISPLAY 0.872340 (-6175 5025);
DISPLAY INVISIBLE (-6175 5025);
FORCEPROP 1 LAST PATH I265
J 2
(-5848 5150);
DISPLAY 0.872340 (-5848 5150);
PAINT GREEN (-5848 5150);
DISPLAY INVISIBLE (-5848 5150);
FORCEADD TAP..1
R 2
(-6050 5600);
FORCEPROP 3 LASTPIN (-6000 5600) SIG_NAME M_G_CPU0_SA_DQS_DN<4>
J 0
(-5990 5610);
DISPLAY 0.659574 (-5990 5610);
PAINT MONO (-5990 5610);
DISPLAY INVISIBLE (-5990 5610);
FORCEPROP 1 LASTPIN (-6000 5600) BN 4
J 2
(-5988 5608);
DISPLAY 0.489362 (-5988 5608);
PAINT GREEN (-5988 5608);
FORCEPROP 2 LAST CDS_LIB mstr_standard
J 2
(-6050 5600);
DISPLAY 0.723404 (-6050 5600);
PAINT MONO (-6050 5600);
DISPLAY INVISIBLE (-6050 5600);
FORCEPROP 1 LAST BODY_TYPE PLUMBING
J 2
(-6050 5650);
DISPLAY 0.872340 (-6050 5650);
PAINT GREEN (-6050 5650);
DISPLAY INVISIBLE (-6050 5650);
FORCEPROP 1 LAST HDL_TAP TRUE
J 2
(-6375 5475);
DISPLAY 0.872340 (-6375 5475);
DISPLAY INVISIBLE (-6375 5475);
FORCEPROP 1 LAST PATH I266
J 2
(-6048 5600);
DISPLAY 0.872340 (-6048 5600);
PAINT GREEN (-6048 5600);
DISPLAY INVISIBLE (-6048 5600);
FORCEADD TAP..1
R 2
(-6050 5500);
FORCEPROP 3 LASTPIN (-6000 5500) SIG_NAME M_G_CPU0_SA_DQS_DN<5>
J 0
(-5990 5510);
DISPLAY 0.659574 (-5990 5510);
PAINT MONO (-5990 5510);
DISPLAY INVISIBLE (-5990 5510);
FORCEPROP 1 LASTPIN (-6000 5500) BN 5
J 2
(-5988 5508);
DISPLAY 0.489362 (-5988 5508);
PAINT GREEN (-5988 5508);
FORCEPROP 2 LAST CDS_LIB mstr_standard
J 2
(-6050 5500);
DISPLAY 0.723404 (-6050 5500);
PAINT MONO (-6050 5500);
DISPLAY INVISIBLE (-6050 5500);
FORCEPROP 1 LAST BODY_TYPE PLUMBING
J 2
(-6050 5550);
DISPLAY 0.872340 (-6050 5550);
PAINT GREEN (-6050 5550);
DISPLAY INVISIBLE (-6050 5550);
FORCEPROP 1 LAST HDL_TAP TRUE
J 2
(-6375 5375);
DISPLAY 0.872340 (-6375 5375);
DISPLAY INVISIBLE (-6375 5375);
FORCEPROP 1 LAST PATH I267
J 2
(-6048 5500);
DISPLAY 0.872340 (-6048 5500);
PAINT GREEN (-6048 5500);
DISPLAY INVISIBLE (-6048 5500);
FORCEADD TAP..1
R 2
(-6050 5400);
FORCEPROP 3 LASTPIN (-6000 5400) SIG_NAME M_G_CPU0_SA_DQS_DN<6>
J 0
(-5990 5410);
DISPLAY 0.659574 (-5990 5410);
PAINT MONO (-5990 5410);
DISPLAY INVISIBLE (-5990 5410);
FORCEPROP 1 LASTPIN (-6000 5400) BN 6
J 2
(-5988 5408);
DISPLAY 0.489362 (-5988 5408);
PAINT GREEN (-5988 5408);
FORCEPROP 2 LAST CDS_LIB mstr_standard
J 2
(-6050 5400);
DISPLAY 0.723404 (-6050 5400);
PAINT MONO (-6050 5400);
DISPLAY INVISIBLE (-6050 5400);
FORCEPROP 1 LAST BODY_TYPE PLUMBING
J 2
(-6050 5450);
DISPLAY 0.872340 (-6050 5450);
PAINT GREEN (-6050 5450);
DISPLAY INVISIBLE (-6050 5450);
FORCEPROP 1 LAST HDL_TAP TRUE
J 2
(-6375 5275);
DISPLAY 0.872340 (-6375 5275);
DISPLAY INVISIBLE (-6375 5275);
FORCEPROP 1 LAST PATH I268
J 2
(-6048 5400);
DISPLAY 0.872340 (-6048 5400);
PAINT GREEN (-6048 5400);
DISPLAY INVISIBLE (-6048 5400);
FORCEADD TAP..1
R 2
(-6050 5300);
FORCEPROP 3 LASTPIN (-6000 5300) SIG_NAME M_G_CPU0_SA_DQS_DN<7>
J 0
(-5990 5310);
DISPLAY 0.659574 (-5990 5310);
PAINT MONO (-5990 5310);
DISPLAY INVISIBLE (-5990 5310);
FORCEPROP 1 LASTPIN (-6000 5300) BN 7
J 2
(-5988 5308);
DISPLAY 0.489362 (-5988 5308);
PAINT GREEN (-5988 5308);
FORCEPROP 2 LAST CDS_LIB mstr_standard
J 2
(-6050 5300);
DISPLAY 0.723404 (-6050 5300);
PAINT MONO (-6050 5300);
DISPLAY INVISIBLE (-6050 5300);
FORCEPROP 1 LAST BODY_TYPE PLUMBING
J 2
(-6050 5350);
DISPLAY 0.872340 (-6050 5350);
PAINT GREEN (-6050 5350);
DISPLAY INVISIBLE (-6050 5350);
FORCEPROP 1 LAST HDL_TAP TRUE
J 2
(-6375 5175);
DISPLAY 0.872340 (-6375 5175);
DISPLAY INVISIBLE (-6375 5175);
FORCEPROP 1 LAST PATH I269
J 2
(-6048 5300);
DISPLAY 0.872340 (-6048 5300);
PAINT GREEN (-6048 5300);
DISPLAY INVISIBLE (-6048 5300);
FORCEADD TAP..1
R 2
(-6050 5200);
FORCEPROP 3 LASTPIN (-6000 5200) SIG_NAME M_G_CPU0_SA_DQS_DN<8>
J 0
(-5990 5210);
DISPLAY 0.659574 (-5990 5210);
PAINT MONO (-5990 5210);
DISPLAY INVISIBLE (-5990 5210);
FORCEPROP 1 LASTPIN (-6000 5200) BN 8
J 2
(-5988 5208);
DISPLAY 0.489362 (-5988 5208);
PAINT GREEN (-5988 5208);
FORCEPROP 2 LAST CDS_LIB mstr_standard
J 2
(-6050 5200);
DISPLAY 0.723404 (-6050 5200);
PAINT MONO (-6050 5200);
DISPLAY INVISIBLE (-6050 5200);
FORCEPROP 1 LAST BODY_TYPE PLUMBING
J 2
(-6050 5250);
DISPLAY 0.872340 (-6050 5250);
PAINT GREEN (-6050 5250);
DISPLAY INVISIBLE (-6050 5250);
FORCEPROP 1 LAST HDL_TAP TRUE
J 2
(-6375 5075);
DISPLAY 0.872340 (-6375 5075);
DISPLAY INVISIBLE (-6375 5075);
FORCEPROP 1 LAST PATH I270
J 2
(-6048 5200);
DISPLAY 0.872340 (-6048 5200);
PAINT GREEN (-6048 5200);
DISPLAY INVISIBLE (-6048 5200);
FORCEADD TAP..1
R 2
(-5850 5000);
FORCEPROP 3 LASTPIN (-5800 5000) SIG_NAME M_G_CPU0_SB_DQS_DP<0>
J 0
(-5790 5010);
DISPLAY 0.659574 (-5790 5010);
PAINT MONO (-5790 5010);
DISPLAY INVISIBLE (-5790 5010);
FORCEPROP 1 LASTPIN (-5800 5000) BN 0
J 2
(-5788 5008);
DISPLAY 0.489362 (-5788 5008);
PAINT GREEN (-5788 5008);
FORCEPROP 2 LAST CDS_LIB mstr_standard
J 2
(-5850 5000);
DISPLAY 0.723404 (-5850 5000);
PAINT MONO (-5850 5000);
DISPLAY INVISIBLE (-5850 5000);
FORCEPROP 1 LAST BODY_TYPE PLUMBING
J 2
(-5850 5050);
DISPLAY 0.872340 (-5850 5050);
PAINT GREEN (-5850 5050);
DISPLAY INVISIBLE (-5850 5050);
FORCEPROP 1 LAST HDL_TAP TRUE
J 2
(-6175 4875);
DISPLAY 0.872340 (-6175 4875);
DISPLAY INVISIBLE (-6175 4875);
FORCEPROP 1 LAST PATH I271
J 2
(-5848 5000);
DISPLAY 0.872340 (-5848 5000);
PAINT GREEN (-5848 5000);
DISPLAY INVISIBLE (-5848 5000);
FORCEADD TAP..1
R 2
(-5850 4900);
FORCEPROP 3 LASTPIN (-5800 4900) SIG_NAME M_G_CPU0_SB_DQS_DP<1>
J 0
(-5790 4910);
DISPLAY 0.659574 (-5790 4910);
PAINT MONO (-5790 4910);
DISPLAY INVISIBLE (-5790 4910);
FORCEPROP 1 LASTPIN (-5800 4900) BN 1
J 2
(-5788 4908);
DISPLAY 0.489362 (-5788 4908);
PAINT GREEN (-5788 4908);
FORCEPROP 2 LAST CDS_LIB mstr_standard
J 2
(-5850 4900);
DISPLAY 0.723404 (-5850 4900);
PAINT MONO (-5850 4900);
DISPLAY INVISIBLE (-5850 4900);
FORCEPROP 1 LAST BODY_TYPE PLUMBING
J 2
(-5850 4950);
DISPLAY 0.872340 (-5850 4950);
PAINT GREEN (-5850 4950);
DISPLAY INVISIBLE (-5850 4950);
FORCEPROP 1 LAST HDL_TAP TRUE
J 2
(-6175 4775);
DISPLAY 0.872340 (-6175 4775);
DISPLAY INVISIBLE (-6175 4775);
FORCEPROP 1 LAST PATH I272
J 2
(-5848 4900);
DISPLAY 0.872340 (-5848 4900);
PAINT GREEN (-5848 4900);
DISPLAY INVISIBLE (-5848 4900);
FORCEADD TAP..1
R 2
(-5850 4800);
FORCEPROP 3 LASTPIN (-5800 4800) SIG_NAME M_G_CPU0_SB_DQS_DP<2>
J 0
(-5790 4810);
DISPLAY 0.659574 (-5790 4810);
PAINT MONO (-5790 4810);
DISPLAY INVISIBLE (-5790 4810);
FORCEPROP 1 LASTPIN (-5800 4800) BN 2
J 2
(-5788 4808);
DISPLAY 0.489362 (-5788 4808);
PAINT GREEN (-5788 4808);
FORCEPROP 2 LAST CDS_LIB mstr_standard
J 2
(-5850 4800);
DISPLAY 0.723404 (-5850 4800);
PAINT MONO (-5850 4800);
DISPLAY INVISIBLE (-5850 4800);
FORCEPROP 1 LAST BODY_TYPE PLUMBING
J 2
(-5850 4850);
DISPLAY 0.872340 (-5850 4850);
PAINT GREEN (-5850 4850);
DISPLAY INVISIBLE (-5850 4850);
FORCEPROP 1 LAST HDL_TAP TRUE
J 2
(-6175 4675);
DISPLAY 0.872340 (-6175 4675);
DISPLAY INVISIBLE (-6175 4675);
FORCEPROP 1 LAST PATH I273
J 2
(-5848 4800);
DISPLAY 0.872340 (-5848 4800);
PAINT GREEN (-5848 4800);
DISPLAY INVISIBLE (-5848 4800);
FORCEADD TAP..1
R 2
(-5850 4700);
FORCEPROP 3 LASTPIN (-5800 4700) SIG_NAME M_G_CPU0_SB_DQS_DP<3>
J 0
(-5790 4710);
DISPLAY 0.659574 (-5790 4710);
PAINT MONO (-5790 4710);
DISPLAY INVISIBLE (-5790 4710);
FORCEPROP 1 LASTPIN (-5800 4700) BN 3
J 2
(-5788 4708);
DISPLAY 0.489362 (-5788 4708);
PAINT GREEN (-5788 4708);
FORCEPROP 2 LAST CDS_LIB mstr_standard
J 2
(-5850 4700);
DISPLAY 0.723404 (-5850 4700);
PAINT MONO (-5850 4700);
DISPLAY INVISIBLE (-5850 4700);
FORCEPROP 1 LAST BODY_TYPE PLUMBING
J 2
(-5850 4750);
DISPLAY 0.872340 (-5850 4750);
PAINT GREEN (-5850 4750);
DISPLAY INVISIBLE (-5850 4750);
FORCEPROP 1 LAST HDL_TAP TRUE
J 2
(-6175 4575);
DISPLAY 0.872340 (-6175 4575);
DISPLAY INVISIBLE (-6175 4575);
FORCEPROP 1 LAST PATH I274
J 2
(-5848 4700);
DISPLAY 0.872340 (-5848 4700);
PAINT GREEN (-5848 4700);
DISPLAY INVISIBLE (-5848 4700);
FORCEADD TAP..1
R 2
(-6050 5100);
FORCEPROP 3 LASTPIN (-6000 5100) SIG_NAME M_G_CPU0_SA_DQS_DN<9>
J 0
(-5990 5110);
DISPLAY 0.659574 (-5990 5110);
PAINT MONO (-5990 5110);
DISPLAY INVISIBLE (-5990 5110);
FORCEPROP 1 LASTPIN (-6000 5100) BN 9
J 2
(-5988 5108);
DISPLAY 0.489362 (-5988 5108);
PAINT GREEN (-5988 5108);
FORCEPROP 2 LAST CDS_LIB mstr_standard
J 2
(-6050 5100);
DISPLAY 0.723404 (-6050 5100);
PAINT MONO (-6050 5100);
DISPLAY INVISIBLE (-6050 5100);
FORCEPROP 1 LAST BODY_TYPE PLUMBING
J 2
(-6050 5150);
DISPLAY 0.872340 (-6050 5150);
PAINT GREEN (-6050 5150);
DISPLAY INVISIBLE (-6050 5150);
FORCEPROP 1 LAST HDL_TAP TRUE
J 2
(-6375 4975);
DISPLAY 0.872340 (-6375 4975);
DISPLAY INVISIBLE (-6375 4975);
FORCEPROP 1 LAST PATH I275
J 2
(-6048 5100);
DISPLAY 0.872340 (-6048 5100);
PAINT GREEN (-6048 5100);
DISPLAY INVISIBLE (-6048 5100);
FORCEADD TAP..1
R 2
(-6050 4950);
FORCEPROP 3 LASTPIN (-6000 4950) SIG_NAME M_G_CPU0_SB_DQS_DN<0>
J 0
(-5990 4960);
DISPLAY 0.659574 (-5990 4960);
PAINT MONO (-5990 4960);
DISPLAY INVISIBLE (-5990 4960);
FORCEPROP 1 LASTPIN (-6000 4950) BN 0
J 2
(-5988 4958);
DISPLAY 0.489362 (-5988 4958);
PAINT GREEN (-5988 4958);
FORCEPROP 2 LAST CDS_LIB mstr_standard
J 2
(-6050 4950);
DISPLAY 0.723404 (-6050 4950);
PAINT MONO (-6050 4950);
DISPLAY INVISIBLE (-6050 4950);
FORCEPROP 1 LAST BODY_TYPE PLUMBING
J 2
(-6050 5000);
DISPLAY 0.872340 (-6050 5000);
PAINT GREEN (-6050 5000);
DISPLAY INVISIBLE (-6050 5000);
FORCEPROP 1 LAST HDL_TAP TRUE
J 2
(-6375 4825);
DISPLAY 0.872340 (-6375 4825);
DISPLAY INVISIBLE (-6375 4825);
FORCEPROP 1 LAST PATH I276
J 2
(-6048 4950);
DISPLAY 0.872340 (-6048 4950);
PAINT GREEN (-6048 4950);
DISPLAY INVISIBLE (-6048 4950);
FORCEADD TAP..1
R 2
(-6050 4850);
FORCEPROP 3 LASTPIN (-6000 4850) SIG_NAME M_G_CPU0_SB_DQS_DN<1>
J 0
(-5990 4860);
DISPLAY 0.659574 (-5990 4860);
PAINT MONO (-5990 4860);
DISPLAY INVISIBLE (-5990 4860);
FORCEPROP 1 LASTPIN (-6000 4850) BN 1
J 2
(-5988 4858);
DISPLAY 0.489362 (-5988 4858);
PAINT GREEN (-5988 4858);
FORCEPROP 2 LAST CDS_LIB mstr_standard
J 2
(-6050 4850);
DISPLAY 0.723404 (-6050 4850);
PAINT MONO (-6050 4850);
DISPLAY INVISIBLE (-6050 4850);
FORCEPROP 1 LAST BODY_TYPE PLUMBING
J 2
(-6050 4900);
DISPLAY 0.872340 (-6050 4900);
PAINT GREEN (-6050 4900);
DISPLAY INVISIBLE (-6050 4900);
FORCEPROP 1 LAST HDL_TAP TRUE
J 2
(-6375 4725);
DISPLAY 0.872340 (-6375 4725);
DISPLAY INVISIBLE (-6375 4725);
FORCEPROP 1 LAST PATH I277
J 2
(-6048 4850);
DISPLAY 0.872340 (-6048 4850);
PAINT GREEN (-6048 4850);
DISPLAY INVISIBLE (-6048 4850);
FORCEADD TAP..1
R 2
(-6050 4750);
FORCEPROP 3 LASTPIN (-6000 4750) SIG_NAME M_G_CPU0_SB_DQS_DN<2>
J 0
(-5990 4760);
DISPLAY 0.659574 (-5990 4760);
PAINT MONO (-5990 4760);
DISPLAY INVISIBLE (-5990 4760);
FORCEPROP 1 LASTPIN (-6000 4750) BN 2
J 2
(-5988 4758);
DISPLAY 0.489362 (-5988 4758);
PAINT GREEN (-5988 4758);
FORCEPROP 2 LAST CDS_LIB mstr_standard
J 2
(-6050 4750);
DISPLAY 0.723404 (-6050 4750);
PAINT MONO (-6050 4750);
DISPLAY INVISIBLE (-6050 4750);
FORCEPROP 1 LAST BODY_TYPE PLUMBING
J 2
(-6050 4800);
DISPLAY 0.872340 (-6050 4800);
PAINT GREEN (-6050 4800);
DISPLAY INVISIBLE (-6050 4800);
FORCEPROP 1 LAST HDL_TAP TRUE
J 2
(-6375 4625);
DISPLAY 0.872340 (-6375 4625);
DISPLAY INVISIBLE (-6375 4625);
FORCEPROP 1 LAST PATH I278
J 2
(-6048 4750);
DISPLAY 0.872340 (-6048 4750);
PAINT GREEN (-6048 4750);
DISPLAY INVISIBLE (-6048 4750);
FORCEADD TAP..1
R 2
(-6050 4650);
FORCEPROP 3 LASTPIN (-6000 4650) SIG_NAME M_G_CPU0_SB_DQS_DN<3>
J 0
(-5990 4660);
DISPLAY 0.659574 (-5990 4660);
PAINT MONO (-5990 4660);
DISPLAY INVISIBLE (-5990 4660);
FORCEPROP 1 LASTPIN (-6000 4650) BN 3
J 2
(-5988 4658);
DISPLAY 0.489362 (-5988 4658);
PAINT GREEN (-5988 4658);
FORCEPROP 2 LAST CDS_LIB mstr_standard
J 2
(-6050 4650);
DISPLAY 0.723404 (-6050 4650);
PAINT MONO (-6050 4650);
DISPLAY INVISIBLE (-6050 4650);
FORCEPROP 1 LAST BODY_TYPE PLUMBING
J 2
(-6050 4700);
DISPLAY 0.872340 (-6050 4700);
PAINT GREEN (-6050 4700);
DISPLAY INVISIBLE (-6050 4700);
FORCEPROP 1 LAST HDL_TAP TRUE
J 2
(-6375 4525);
DISPLAY 0.872340 (-6375 4525);
DISPLAY INVISIBLE (-6375 4525);
FORCEPROP 1 LAST PATH I279
J 2
(-6048 4650);
DISPLAY 0.872340 (-6048 4650);
PAINT GREEN (-6048 4650);
DISPLAY INVISIBLE (-6048 4650);
FORCEADD TAP..1
R 2
(-5850 4600);
FORCEPROP 3 LASTPIN (-5800 4600) SIG_NAME M_G_CPU0_SB_DQS_DP<4>
J 0
(-5790 4610);
DISPLAY 0.659574 (-5790 4610);
PAINT MONO (-5790 4610);
DISPLAY INVISIBLE (-5790 4610);
FORCEPROP 1 LASTPIN (-5800 4600) BN 4
J 2
(-5788 4608);
DISPLAY 0.489362 (-5788 4608);
PAINT GREEN (-5788 4608);
FORCEPROP 2 LAST CDS_LIB mstr_standard
J 2
(-5850 4600);
DISPLAY 0.723404 (-5850 4600);
PAINT MONO (-5850 4600);
DISPLAY INVISIBLE (-5850 4600);
FORCEPROP 1 LAST BODY_TYPE PLUMBING
J 2
(-5850 4650);
DISPLAY 0.872340 (-5850 4650);
PAINT GREEN (-5850 4650);
DISPLAY INVISIBLE (-5850 4650);
FORCEPROP 1 LAST HDL_TAP TRUE
J 2
(-6175 4475);
DISPLAY 0.872340 (-6175 4475);
DISPLAY INVISIBLE (-6175 4475);
FORCEPROP 1 LAST PATH I280
J 2
(-5848 4600);
DISPLAY 0.872340 (-5848 4600);
PAINT GREEN (-5848 4600);
DISPLAY INVISIBLE (-5848 4600);
FORCEADD TAP..1
R 2
(-5850 4400);
FORCEPROP 3 LASTPIN (-5800 4400) SIG_NAME M_G_CPU0_SB_DQS_DP<6>
J 0
(-5790 4410);
DISPLAY 0.659574 (-5790 4410);
PAINT MONO (-5790 4410);
DISPLAY INVISIBLE (-5790 4410);
FORCEPROP 1 LASTPIN (-5800 4400) BN 6
J 2
(-5788 4408);
DISPLAY 0.489362 (-5788 4408);
PAINT GREEN (-5788 4408);
FORCEPROP 2 LAST CDS_LIB mstr_standard
J 2
(-5850 4400);
DISPLAY 0.723404 (-5850 4400);
PAINT MONO (-5850 4400);
DISPLAY INVISIBLE (-5850 4400);
FORCEPROP 1 LAST BODY_TYPE PLUMBING
J 2
(-5850 4450);
DISPLAY 0.872340 (-5850 4450);
PAINT GREEN (-5850 4450);
DISPLAY INVISIBLE (-5850 4450);
FORCEPROP 1 LAST HDL_TAP TRUE
J 2
(-6175 4275);
DISPLAY 0.872340 (-6175 4275);
DISPLAY INVISIBLE (-6175 4275);
FORCEPROP 1 LAST PATH I281
J 2
(-5848 4400);
DISPLAY 0.872340 (-5848 4400);
PAINT GREEN (-5848 4400);
DISPLAY INVISIBLE (-5848 4400);
FORCEADD TAP..1
R 2
(-5850 4500);
FORCEPROP 3 LASTPIN (-5800 4500) SIG_NAME M_G_CPU0_SB_DQS_DP<5>
J 0
(-5790 4510);
DISPLAY 0.659574 (-5790 4510);
PAINT MONO (-5790 4510);
DISPLAY INVISIBLE (-5790 4510);
FORCEPROP 1 LASTPIN (-5800 4500) BN 5
J 2
(-5788 4508);
DISPLAY 0.489362 (-5788 4508);
PAINT GREEN (-5788 4508);
FORCEPROP 2 LAST CDS_LIB mstr_standard
J 2
(-5850 4500);
DISPLAY 0.723404 (-5850 4500);
PAINT MONO (-5850 4500);
DISPLAY INVISIBLE (-5850 4500);
FORCEPROP 1 LAST BODY_TYPE PLUMBING
J 2
(-5850 4550);
DISPLAY 0.872340 (-5850 4550);
PAINT GREEN (-5850 4550);
DISPLAY INVISIBLE (-5850 4550);
FORCEPROP 1 LAST HDL_TAP TRUE
J 2
(-6175 4375);
DISPLAY 0.872340 (-6175 4375);
DISPLAY INVISIBLE (-6175 4375);
FORCEPROP 1 LAST PATH I282
J 2
(-5848 4500);
DISPLAY 0.872340 (-5848 4500);
PAINT GREEN (-5848 4500);
DISPLAY INVISIBLE (-5848 4500);
FORCEADD TAP..1
R 2
(-5850 4300);
FORCEPROP 3 LASTPIN (-5800 4300) SIG_NAME M_G_CPU0_SB_DQS_DP<7>
J 0
(-5790 4310);
DISPLAY 0.659574 (-5790 4310);
PAINT MONO (-5790 4310);
DISPLAY INVISIBLE (-5790 4310);
FORCEPROP 1 LASTPIN (-5800 4300) BN 7
J 2
(-5788 4308);
DISPLAY 0.489362 (-5788 4308);
PAINT GREEN (-5788 4308);
FORCEPROP 2 LAST CDS_LIB mstr_standard
J 2
(-5850 4300);
DISPLAY 0.723404 (-5850 4300);
PAINT MONO (-5850 4300);
DISPLAY INVISIBLE (-5850 4300);
FORCEPROP 1 LAST BODY_TYPE PLUMBING
J 2
(-5850 4350);
DISPLAY 0.872340 (-5850 4350);
PAINT GREEN (-5850 4350);
DISPLAY INVISIBLE (-5850 4350);
FORCEPROP 1 LAST HDL_TAP TRUE
J 2
(-6175 4175);
DISPLAY 0.872340 (-6175 4175);
DISPLAY INVISIBLE (-6175 4175);
FORCEPROP 1 LAST PATH I283
J 2
(-5848 4300);
DISPLAY 0.872340 (-5848 4300);
PAINT GREEN (-5848 4300);
DISPLAY INVISIBLE (-5848 4300);
FORCEADD TAP..1
R 2
(-5850 4200);
FORCEPROP 3 LASTPIN (-5800 4200) SIG_NAME M_G_CPU0_SB_DQS_DP<8>
J 0
(-5790 4210);
DISPLAY 0.659574 (-5790 4210);
PAINT MONO (-5790 4210);
DISPLAY INVISIBLE (-5790 4210);
FORCEPROP 1 LASTPIN (-5800 4200) BN 8
J 2
(-5788 4208);
DISPLAY 0.489362 (-5788 4208);
PAINT GREEN (-5788 4208);
FORCEPROP 2 LAST CDS_LIB mstr_standard
J 2
(-5850 4200);
DISPLAY 0.723404 (-5850 4200);
PAINT MONO (-5850 4200);
DISPLAY INVISIBLE (-5850 4200);
FORCEPROP 1 LAST BODY_TYPE PLUMBING
J 2
(-5850 4250);
DISPLAY 0.872340 (-5850 4250);
PAINT GREEN (-5850 4250);
DISPLAY INVISIBLE (-5850 4250);
FORCEPROP 1 LAST HDL_TAP TRUE
J 2
(-6175 4075);
DISPLAY 0.872340 (-6175 4075);
DISPLAY INVISIBLE (-6175 4075);
FORCEPROP 1 LAST PATH I284
J 2
(-5848 4200);
DISPLAY 0.872340 (-5848 4200);
PAINT GREEN (-5848 4200);
DISPLAY INVISIBLE (-5848 4200);
FORCEADD TAP..1
R 2
(-5850 4100);
FORCEPROP 3 LASTPIN (-5800 4100) SIG_NAME M_G_CPU0_SB_DQS_DP<9>
J 0
(-5790 4110);
DISPLAY 0.659574 (-5790 4110);
PAINT MONO (-5790 4110);
DISPLAY INVISIBLE (-5790 4110);
FORCEPROP 1 LASTPIN (-5800 4100) BN 9
J 2
(-5788 4108);
DISPLAY 0.489362 (-5788 4108);
PAINT GREEN (-5788 4108);
FORCEPROP 2 LAST CDS_LIB mstr_standard
J 2
(-5850 4100);
DISPLAY 0.723404 (-5850 4100);
PAINT MONO (-5850 4100);
DISPLAY INVISIBLE (-5850 4100);
FORCEPROP 1 LAST BODY_TYPE PLUMBING
J 2
(-5850 4150);
DISPLAY 0.872340 (-5850 4150);
PAINT GREEN (-5850 4150);
DISPLAY INVISIBLE (-5850 4150);
FORCEPROP 1 LAST HDL_TAP TRUE
J 2
(-6175 3975);
DISPLAY 0.872340 (-6175 3975);
DISPLAY INVISIBLE (-6175 3975);
FORCEPROP 1 LAST PATH I285
J 2
(-5848 4100);
DISPLAY 0.872340 (-5848 4100);
PAINT GREEN (-5848 4100);
DISPLAY INVISIBLE (-5848 4100);
FORCEADD TAP..1
R 2
(-6050 4550);
FORCEPROP 3 LASTPIN (-6000 4550) SIG_NAME M_G_CPU0_SB_DQS_DN<4>
J 0
(-5990 4560);
DISPLAY 0.659574 (-5990 4560);
PAINT MONO (-5990 4560);
DISPLAY INVISIBLE (-5990 4560);
FORCEPROP 1 LASTPIN (-6000 4550) BN 4
J 2
(-5988 4558);
DISPLAY 0.489362 (-5988 4558);
PAINT GREEN (-5988 4558);
FORCEPROP 2 LAST CDS_LIB mstr_standard
J 2
(-6050 4550);
DISPLAY 0.723404 (-6050 4550);
PAINT MONO (-6050 4550);
DISPLAY INVISIBLE (-6050 4550);
FORCEPROP 1 LAST BODY_TYPE PLUMBING
J 2
(-6050 4600);
DISPLAY 0.872340 (-6050 4600);
PAINT GREEN (-6050 4600);
DISPLAY INVISIBLE (-6050 4600);
FORCEPROP 1 LAST HDL_TAP TRUE
J 2
(-6375 4425);
DISPLAY 0.872340 (-6375 4425);
DISPLAY INVISIBLE (-6375 4425);
FORCEPROP 1 LAST PATH I286
J 2
(-6048 4550);
DISPLAY 0.872340 (-6048 4550);
PAINT GREEN (-6048 4550);
DISPLAY INVISIBLE (-6048 4550);
FORCEADD TAP..1
R 2
(-6050 4450);
FORCEPROP 3 LASTPIN (-6000 4450) SIG_NAME M_G_CPU0_SB_DQS_DN<5>
J 0
(-5990 4460);
DISPLAY 0.659574 (-5990 4460);
PAINT MONO (-5990 4460);
DISPLAY INVISIBLE (-5990 4460);
FORCEPROP 1 LASTPIN (-6000 4450) BN 5
J 2
(-5988 4458);
DISPLAY 0.489362 (-5988 4458);
PAINT GREEN (-5988 4458);
FORCEPROP 2 LAST CDS_LIB mstr_standard
J 2
(-6050 4450);
DISPLAY 0.723404 (-6050 4450);
PAINT MONO (-6050 4450);
DISPLAY INVISIBLE (-6050 4450);
FORCEPROP 1 LAST BODY_TYPE PLUMBING
J 2
(-6050 4500);
DISPLAY 0.872340 (-6050 4500);
PAINT GREEN (-6050 4500);
DISPLAY INVISIBLE (-6050 4500);
FORCEPROP 1 LAST HDL_TAP TRUE
J 2
(-6375 4325);
DISPLAY 0.872340 (-6375 4325);
DISPLAY INVISIBLE (-6375 4325);
FORCEPROP 1 LAST PATH I287
J 2
(-6048 4450);
DISPLAY 0.872340 (-6048 4450);
PAINT GREEN (-6048 4450);
DISPLAY INVISIBLE (-6048 4450);
FORCEADD TAP..1
R 2
(-6050 4250);
FORCEPROP 3 LASTPIN (-6000 4250) SIG_NAME M_G_CPU0_SB_DQS_DN<7>
J 0
(-5990 4260);
DISPLAY 0.659574 (-5990 4260);
PAINT MONO (-5990 4260);
DISPLAY INVISIBLE (-5990 4260);
FORCEPROP 1 LASTPIN (-6000 4250) BN 7
J 2
(-5988 4258);
DISPLAY 0.489362 (-5988 4258);
PAINT GREEN (-5988 4258);
FORCEPROP 2 LAST CDS_LIB mstr_standard
J 2
(-6050 4250);
DISPLAY 0.723404 (-6050 4250);
PAINT MONO (-6050 4250);
DISPLAY INVISIBLE (-6050 4250);
FORCEPROP 1 LAST BODY_TYPE PLUMBING
J 2
(-6050 4300);
DISPLAY 0.872340 (-6050 4300);
PAINT GREEN (-6050 4300);
DISPLAY INVISIBLE (-6050 4300);
FORCEPROP 1 LAST HDL_TAP TRUE
J 2
(-6375 4125);
DISPLAY 0.872340 (-6375 4125);
DISPLAY INVISIBLE (-6375 4125);
FORCEPROP 1 LAST PATH I288
J 2
(-6048 4250);
DISPLAY 0.872340 (-6048 4250);
PAINT GREEN (-6048 4250);
DISPLAY INVISIBLE (-6048 4250);
FORCEADD TAP..1
R 2
(-6050 4350);
FORCEPROP 3 LASTPIN (-6000 4350) SIG_NAME M_G_CPU0_SB_DQS_DN<6>
J 0
(-5990 4360);
DISPLAY 0.659574 (-5990 4360);
PAINT MONO (-5990 4360);
DISPLAY INVISIBLE (-5990 4360);
FORCEPROP 1 LASTPIN (-6000 4350) BN 6
J 2
(-5988 4358);
DISPLAY 0.489362 (-5988 4358);
PAINT GREEN (-5988 4358);
FORCEPROP 2 LAST CDS_LIB mstr_standard
J 2
(-6050 4350);
DISPLAY 0.723404 (-6050 4350);
PAINT MONO (-6050 4350);
DISPLAY INVISIBLE (-6050 4350);
FORCEPROP 1 LAST BODY_TYPE PLUMBING
J 2
(-6050 4400);
DISPLAY 0.872340 (-6050 4400);
PAINT GREEN (-6050 4400);
DISPLAY INVISIBLE (-6050 4400);
FORCEPROP 1 LAST HDL_TAP TRUE
J 2
(-6375 4225);
DISPLAY 0.872340 (-6375 4225);
DISPLAY INVISIBLE (-6375 4225);
FORCEPROP 1 LAST PATH I289
J 2
(-6048 4350);
DISPLAY 0.872340 (-6048 4350);
PAINT GREEN (-6048 4350);
DISPLAY INVISIBLE (-6048 4350);
FORCEADD TAP..1
R 2
(-6050 4150);
FORCEPROP 3 LASTPIN (-6000 4150) SIG_NAME M_G_CPU0_SB_DQS_DN<8>
J 0
(-5990 4160);
DISPLAY 0.659574 (-5990 4160);
PAINT MONO (-5990 4160);
DISPLAY INVISIBLE (-5990 4160);
FORCEPROP 1 LASTPIN (-6000 4150) BN 8
J 2
(-5988 4158);
DISPLAY 0.489362 (-5988 4158);
PAINT GREEN (-5988 4158);
FORCEPROP 2 LAST CDS_LIB mstr_standard
J 2
(-6050 4150);
DISPLAY 0.723404 (-6050 4150);
PAINT MONO (-6050 4150);
DISPLAY INVISIBLE (-6050 4150);
FORCEPROP 1 LAST BODY_TYPE PLUMBING
J 2
(-6050 4200);
DISPLAY 0.872340 (-6050 4200);
PAINT GREEN (-6050 4200);
DISPLAY INVISIBLE (-6050 4200);
FORCEPROP 1 LAST HDL_TAP TRUE
J 2
(-6375 4025);
DISPLAY 0.872340 (-6375 4025);
DISPLAY INVISIBLE (-6375 4025);
FORCEPROP 1 LAST PATH I290
J 2
(-6048 4150);
DISPLAY 0.872340 (-6048 4150);
PAINT GREEN (-6048 4150);
DISPLAY INVISIBLE (-6048 4150);
FORCEADD OFFPAGE..3
R 2
(-6750 6075);
FORCEPROP 2 LAST $XR0 91 
J 0
(-6999 6075);
DISPLAY 0.638298 (-6999 6075);
PAINT MONO (-6999 6075);
FORCEPROP 2 LAST PATH I291
J 0
(-7025 6125);
DISPLAY 1.021277 (-7025 6125);
DISPLAY INVISIBLE (-7025 6125);
FORCEPROP 1 LAST COMMENT_BODY TRUE
J 2
(-6700 5975);
DISPLAY 0.872340 (-6700 5975);
PAINT GREEN (-6700 5975);
DISPLAY INVISIBLE (-6700 5975);
FORCEPROP 1 LAST OFFPAGE TRUE
J 2
(-7075 5950);
DISPLAY 0.872340 (-7075 5950);
PAINT GREEN (-7075 5950);
DISPLAY INVISIBLE (-7075 5950);
FORCEPROP 2 LAST CDS_LIB standard
J 0
(-6750 6075);
DISPLAY INVISIBLE (-6750 6075);
FORCEADD OFFPAGE..3
R 2
(-6750 6025);
FORCEPROP 2 LAST $XR0 91 
J 0
(-6999 6025);
DISPLAY 0.638298 (-6999 6025);
PAINT MONO (-6999 6025);
FORCEPROP 2 LAST PATH I292
J 0
(-7025 6075);
DISPLAY 1.021277 (-7025 6075);
DISPLAY INVISIBLE (-7025 6075);
FORCEPROP 1 LAST COMMENT_BODY TRUE
J 2
(-6700 5925);
DISPLAY 0.872340 (-6700 5925);
PAINT GREEN (-6700 5925);
DISPLAY INVISIBLE (-6700 5925);
FORCEPROP 1 LAST OFFPAGE TRUE
J 2
(-7075 5900);
DISPLAY 0.872340 (-7075 5900);
PAINT GREEN (-7075 5900);
DISPLAY INVISIBLE (-7075 5900);
FORCEPROP 2 LAST CDS_LIB standard
J 0
(-6750 6025);
DISPLAY INVISIBLE (-6750 6025);
FORCEADD OFFPAGE..3
R 2
(-6750 5025);
FORCEPROP 2 LAST $XR0 91 
J 0
(-6999 5025);
DISPLAY 0.638298 (-6999 5025);
PAINT MONO (-6999 5025);
FORCEPROP 2 LAST PATH I293
J 0
(-7025 5075);
DISPLAY 1.021277 (-7025 5075);
DISPLAY INVISIBLE (-7025 5075);
FORCEPROP 1 LAST COMMENT_BODY TRUE
J 2
(-6700 4925);
DISPLAY 0.872340 (-6700 4925);
PAINT GREEN (-6700 4925);
DISPLAY INVISIBLE (-6700 4925);
FORCEPROP 1 LAST OFFPAGE TRUE
J 2
(-7075 4900);
DISPLAY 0.872340 (-7075 4900);
PAINT GREEN (-7075 4900);
DISPLAY INVISIBLE (-7075 4900);
FORCEPROP 2 LAST CDS_LIB standard
J 0
(-6750 5025);
DISPLAY INVISIBLE (-6750 5025);
FORCEADD OFFPAGE..3
R 2
(-6750 4975);
FORCEPROP 2 LAST $XR0 91 
J 0
(-6999 4975);
DISPLAY 0.638298 (-6999 4975);
PAINT MONO (-6999 4975);
FORCEPROP 2 LAST PATH I294
J 0
(-7025 5025);
DISPLAY 1.021277 (-7025 5025);
DISPLAY INVISIBLE (-7025 5025);
FORCEPROP 1 LAST COMMENT_BODY TRUE
J 2
(-6700 4875);
DISPLAY 0.872340 (-6700 4875);
PAINT GREEN (-6700 4875);
DISPLAY INVISIBLE (-6700 4875);
FORCEPROP 1 LAST OFFPAGE TRUE
J 2
(-7075 4850);
DISPLAY 0.872340 (-7075 4850);
PAINT GREEN (-7075 4850);
DISPLAY INVISIBLE (-7075 4850);
FORCEPROP 2 LAST CDS_LIB standard
J 0
(-6750 4975);
DISPLAY INVISIBLE (-6750 4975);
FORCEADD TAP..1
R 2
(-6050 4050);
FORCEPROP 3 LASTPIN (-6000 4050) SIG_NAME M_G_CPU0_SB_DQS_DN<9>
J 0
(-5990 4060);
DISPLAY 0.659574 (-5990 4060);
PAINT MONO (-5990 4060);
DISPLAY INVISIBLE (-5990 4060);
FORCEPROP 1 LASTPIN (-6000 4050) BN 9
J 2
(-5988 4058);
DISPLAY 0.489362 (-5988 4058);
PAINT GREEN (-5988 4058);
FORCEPROP 2 LAST CDS_LIB mstr_standard
J 2
(-6050 4050);
DISPLAY 0.723404 (-6050 4050);
PAINT MONO (-6050 4050);
DISPLAY INVISIBLE (-6050 4050);
FORCEPROP 1 LAST BODY_TYPE PLUMBING
J 2
(-6050 4100);
DISPLAY 0.872340 (-6050 4100);
PAINT GREEN (-6050 4100);
DISPLAY INVISIBLE (-6050 4100);
FORCEPROP 1 LAST HDL_TAP TRUE
J 2
(-6375 3925);
DISPLAY 0.872340 (-6375 3925);
DISPLAY INVISIBLE (-6375 3925);
FORCEPROP 1 LAST PATH I295
J 2
(-6048 4050);
DISPLAY 0.872340 (-6048 4050);
PAINT GREEN (-6048 4050);
DISPLAY INVISIBLE (-6048 4050);
FORCEADD TAP..1
R 2
(-6050 3900);
FORCEPROP 3 LASTPIN (-6000 3900) SIG_NAME M_G_CPU0_SA_CA<0>
J 0
(-5990 3910);
DISPLAY 0.659574 (-5990 3910);
PAINT MONO (-5990 3910);
DISPLAY INVISIBLE (-5990 3910);
FORCEPROP 1 LASTPIN (-6000 3900) BN 0
J 2
(-5988 3908);
DISPLAY 0.489362 (-5988 3908);
PAINT GREEN (-5988 3908);
FORCEPROP 2 LAST CDS_LIB mstr_standard
J 0
(-6050 3900);
DISPLAY 0.723404 (-6050 3900);
PAINT MONO (-6050 3900);
DISPLAY INVISIBLE (-6050 3900);
FORCEPROP 1 LAST BODY_TYPE PLUMBING
J 2
(-6050 3950);
DISPLAY 0.872340 (-6050 3950);
PAINT GREEN (-6050 3950);
DISPLAY INVISIBLE (-6050 3950);
FORCEPROP 1 LAST HDL_TAP TRUE
J 2
(-6375 3775);
DISPLAY 0.872340 (-6375 3775);
DISPLAY INVISIBLE (-6375 3775);
FORCEPROP 1 LAST PATH I296
J 2
(-6048 3900);
DISPLAY 0.872340 (-6048 3900);
PAINT GREEN (-6048 3900);
DISPLAY INVISIBLE (-6048 3900);
FORCEADD TAP..1
R 2
(-6050 3850);
FORCEPROP 3 LASTPIN (-6000 3850) SIG_NAME M_G_CPU0_SA_CA<1>
J 0
(-5990 3860);
DISPLAY 0.659574 (-5990 3860);
PAINT MONO (-5990 3860);
DISPLAY INVISIBLE (-5990 3860);
FORCEPROP 1 LASTPIN (-6000 3850) BN 1
J 2
(-5988 3858);
DISPLAY 0.489362 (-5988 3858);
PAINT GREEN (-5988 3858);
FORCEPROP 2 LAST CDS_LIB mstr_standard
J 0
(-6050 3850);
DISPLAY 0.723404 (-6050 3850);
PAINT MONO (-6050 3850);
DISPLAY INVISIBLE (-6050 3850);
FORCEPROP 1 LAST BODY_TYPE PLUMBING
J 2
(-6050 3900);
DISPLAY 0.872340 (-6050 3900);
PAINT GREEN (-6050 3900);
DISPLAY INVISIBLE (-6050 3900);
FORCEPROP 1 LAST HDL_TAP TRUE
J 2
(-6375 3725);
DISPLAY 0.872340 (-6375 3725);
DISPLAY INVISIBLE (-6375 3725);
FORCEPROP 1 LAST PATH I297
J 2
(-6048 3850);
DISPLAY 0.872340 (-6048 3850);
PAINT GREEN (-6048 3850);
DISPLAY INVISIBLE (-6048 3850);
FORCEADD TAP..1
R 2
(-6050 3800);
FORCEPROP 3 LASTPIN (-6000 3800) SIG_NAME M_G_CPU0_SA_CA<2>
J 0
(-5990 3810);
DISPLAY 0.659574 (-5990 3810);
PAINT MONO (-5990 3810);
DISPLAY INVISIBLE (-5990 3810);
FORCEPROP 1 LASTPIN (-6000 3800) BN 2
J 2
(-5988 3808);
DISPLAY 0.489362 (-5988 3808);
PAINT GREEN (-5988 3808);
FORCEPROP 2 LAST CDS_LIB mstr_standard
J 0
(-6050 3800);
DISPLAY 0.723404 (-6050 3800);
PAINT MONO (-6050 3800);
DISPLAY INVISIBLE (-6050 3800);
FORCEPROP 1 LAST BODY_TYPE PLUMBING
J 2
(-6050 3850);
DISPLAY 0.872340 (-6050 3850);
PAINT GREEN (-6050 3850);
DISPLAY INVISIBLE (-6050 3850);
FORCEPROP 1 LAST HDL_TAP TRUE
J 2
(-6375 3675);
DISPLAY 0.872340 (-6375 3675);
DISPLAY INVISIBLE (-6375 3675);
FORCEPROP 1 LAST PATH I298
J 2
(-6048 3800);
DISPLAY 0.872340 (-6048 3800);
PAINT GREEN (-6048 3800);
DISPLAY INVISIBLE (-6048 3800);
FORCEADD TAP..1
R 2
(-6050 3750);
FORCEPROP 3 LASTPIN (-6000 3750) SIG_NAME M_G_CPU0_SA_CA<3>
J 0
(-5990 3760);
DISPLAY 0.659574 (-5990 3760);
PAINT MONO (-5990 3760);
DISPLAY INVISIBLE (-5990 3760);
FORCEPROP 1 LASTPIN (-6000 3750) BN 3
J 2
(-5988 3758);
DISPLAY 0.489362 (-5988 3758);
PAINT GREEN (-5988 3758);
FORCEPROP 2 LAST CDS_LIB mstr_standard
J 0
(-6050 3750);
DISPLAY 0.723404 (-6050 3750);
PAINT MONO (-6050 3750);
DISPLAY INVISIBLE (-6050 3750);
FORCEPROP 1 LAST BODY_TYPE PLUMBING
J 2
(-6050 3800);
DISPLAY 0.872340 (-6050 3800);
PAINT GREEN (-6050 3800);
DISPLAY INVISIBLE (-6050 3800);
FORCEPROP 1 LAST HDL_TAP TRUE
J 2
(-6375 3625);
DISPLAY 0.872340 (-6375 3625);
DISPLAY INVISIBLE (-6375 3625);
FORCEPROP 1 LAST PATH I299
J 2
(-6048 3750);
DISPLAY 0.872340 (-6048 3750);
PAINT GREEN (-6048 3750);
DISPLAY INVISIBLE (-6048 3750);
FORCEADD TAP..1
R 2
(-6050 3700);
FORCEPROP 3 LASTPIN (-6000 3700) SIG_NAME M_G_CPU0_SA_CA<4>
J 0
(-5990 3710);
DISPLAY 0.659574 (-5990 3710);
PAINT MONO (-5990 3710);
DISPLAY INVISIBLE (-5990 3710);
FORCEPROP 1 LASTPIN (-6000 3700) BN 4
J 2
(-5988 3708);
DISPLAY 0.489362 (-5988 3708);
PAINT GREEN (-5988 3708);
FORCEPROP 2 LAST CDS_LIB mstr_standard
J 0
(-6050 3700);
DISPLAY 0.723404 (-6050 3700);
PAINT MONO (-6050 3700);
DISPLAY INVISIBLE (-6050 3700);
FORCEPROP 1 LAST BODY_TYPE PLUMBING
J 2
(-6050 3750);
DISPLAY 0.872340 (-6050 3750);
PAINT GREEN (-6050 3750);
DISPLAY INVISIBLE (-6050 3750);
FORCEPROP 1 LAST HDL_TAP TRUE
J 2
(-6375 3575);
DISPLAY 0.872340 (-6375 3575);
DISPLAY INVISIBLE (-6375 3575);
FORCEPROP 1 LAST PATH I300
J 2
(-6048 3700);
DISPLAY 0.872340 (-6048 3700);
PAINT GREEN (-6048 3700);
DISPLAY INVISIBLE (-6048 3700);
FORCEADD TAP..1
R 2
(-6050 3650);
FORCEPROP 3 LASTPIN (-6000 3650) SIG_NAME M_G_CPU0_SA_CA<5>
J 0
(-5990 3660);
DISPLAY 0.659574 (-5990 3660);
PAINT MONO (-5990 3660);
DISPLAY INVISIBLE (-5990 3660);
FORCEPROP 1 LASTPIN (-6000 3650) BN 5
J 2
(-5988 3658);
DISPLAY 0.489362 (-5988 3658);
PAINT GREEN (-5988 3658);
FORCEPROP 2 LAST CDS_LIB mstr_standard
J 0
(-6050 3650);
DISPLAY 0.723404 (-6050 3650);
PAINT MONO (-6050 3650);
DISPLAY INVISIBLE (-6050 3650);
FORCEPROP 1 LAST BODY_TYPE PLUMBING
J 2
(-6050 3700);
DISPLAY 0.872340 (-6050 3700);
PAINT GREEN (-6050 3700);
DISPLAY INVISIBLE (-6050 3700);
FORCEPROP 1 LAST HDL_TAP TRUE
J 2
(-6375 3525);
DISPLAY 0.872340 (-6375 3525);
DISPLAY INVISIBLE (-6375 3525);
FORCEPROP 1 LAST PATH I301
J 2
(-6048 3650);
DISPLAY 0.872340 (-6048 3650);
PAINT GREEN (-6048 3650);
DISPLAY INVISIBLE (-6048 3650);
FORCEADD TAP..1
R 2
(-6050 3600);
FORCEPROP 3 LASTPIN (-6000 3600) SIG_NAME M_G_CPU0_SA_CA<6>
J 0
(-5990 3610);
DISPLAY 0.659574 (-5990 3610);
PAINT MONO (-5990 3610);
DISPLAY INVISIBLE (-5990 3610);
FORCEPROP 1 LASTPIN (-6000 3600) BN 6
J 2
(-5988 3608);
DISPLAY 0.489362 (-5988 3608);
PAINT GREEN (-5988 3608);
FORCEPROP 2 LAST CDS_LIB mstr_standard
J 0
(-6050 3600);
DISPLAY 0.723404 (-6050 3600);
PAINT MONO (-6050 3600);
DISPLAY INVISIBLE (-6050 3600);
FORCEPROP 1 LAST BODY_TYPE PLUMBING
J 2
(-6050 3650);
DISPLAY 0.872340 (-6050 3650);
PAINT GREEN (-6050 3650);
DISPLAY INVISIBLE (-6050 3650);
FORCEPROP 1 LAST HDL_TAP TRUE
J 2
(-6375 3475);
DISPLAY 0.872340 (-6375 3475);
DISPLAY INVISIBLE (-6375 3475);
FORCEPROP 1 LAST PATH I302
J 2
(-6048 3600);
DISPLAY 0.872340 (-6048 3600);
PAINT GREEN (-6048 3600);
DISPLAY INVISIBLE (-6048 3600);
FORCEADD TAP..1
R 2
(-6050 3500);
FORCEPROP 3 LASTPIN (-6000 3500) SIG_NAME M_G_CPU0_SB_CA<0>
J 0
(-5990 3510);
DISPLAY 0.659574 (-5990 3510);
PAINT MONO (-5990 3510);
DISPLAY INVISIBLE (-5990 3510);
FORCEPROP 1 LASTPIN (-6000 3500) BN 0
J 2
(-5988 3508);
DISPLAY 0.489362 (-5988 3508);
PAINT GREEN (-5988 3508);
FORCEPROP 2 LAST CDS_LIB mstr_standard
J 0
(-6050 3500);
DISPLAY 0.723404 (-6050 3500);
PAINT MONO (-6050 3500);
DISPLAY INVISIBLE (-6050 3500);
FORCEPROP 1 LAST BODY_TYPE PLUMBING
J 2
(-6050 3550);
DISPLAY 0.872340 (-6050 3550);
PAINT GREEN (-6050 3550);
DISPLAY INVISIBLE (-6050 3550);
FORCEPROP 1 LAST HDL_TAP TRUE
J 2
(-6375 3375);
DISPLAY 0.872340 (-6375 3375);
DISPLAY INVISIBLE (-6375 3375);
FORCEPROP 1 LAST PATH I303
J 2
(-6048 3500);
DISPLAY 0.872340 (-6048 3500);
PAINT GREEN (-6048 3500);
DISPLAY INVISIBLE (-6048 3500);
FORCEADD TAP..1
R 2
(-6050 3450);
FORCEPROP 3 LASTPIN (-6000 3450) SIG_NAME M_G_CPU0_SB_CA<1>
J 0
(-5990 3460);
DISPLAY 0.659574 (-5990 3460);
PAINT MONO (-5990 3460);
DISPLAY INVISIBLE (-5990 3460);
FORCEPROP 1 LASTPIN (-6000 3450) BN 1
J 2
(-5988 3458);
DISPLAY 0.489362 (-5988 3458);
PAINT GREEN (-5988 3458);
FORCEPROP 2 LAST CDS_LIB mstr_standard
J 0
(-6050 3450);
DISPLAY 0.723404 (-6050 3450);
PAINT MONO (-6050 3450);
DISPLAY INVISIBLE (-6050 3450);
FORCEPROP 1 LAST BODY_TYPE PLUMBING
J 2
(-6050 3500);
DISPLAY 0.872340 (-6050 3500);
PAINT GREEN (-6050 3500);
DISPLAY INVISIBLE (-6050 3500);
FORCEPROP 1 LAST HDL_TAP TRUE
J 2
(-6375 3325);
DISPLAY 0.872340 (-6375 3325);
DISPLAY INVISIBLE (-6375 3325);
FORCEPROP 1 LAST PATH I304
J 2
(-6048 3450);
DISPLAY 0.872340 (-6048 3450);
PAINT GREEN (-6048 3450);
DISPLAY INVISIBLE (-6048 3450);
FORCEADD TAP..1
R 2
(-6050 3400);
FORCEPROP 3 LASTPIN (-6000 3400) SIG_NAME M_G_CPU0_SB_CA<2>
J 0
(-5990 3410);
DISPLAY 0.659574 (-5990 3410);
PAINT MONO (-5990 3410);
DISPLAY INVISIBLE (-5990 3410);
FORCEPROP 1 LASTPIN (-6000 3400) BN 2
J 2
(-5988 3408);
DISPLAY 0.489362 (-5988 3408);
PAINT GREEN (-5988 3408);
FORCEPROP 2 LAST CDS_LIB mstr_standard
J 0
(-6050 3400);
DISPLAY 0.723404 (-6050 3400);
PAINT MONO (-6050 3400);
DISPLAY INVISIBLE (-6050 3400);
FORCEPROP 1 LAST BODY_TYPE PLUMBING
J 2
(-6050 3450);
DISPLAY 0.872340 (-6050 3450);
PAINT GREEN (-6050 3450);
DISPLAY INVISIBLE (-6050 3450);
FORCEPROP 1 LAST HDL_TAP TRUE
J 2
(-6375 3275);
DISPLAY 0.872340 (-6375 3275);
DISPLAY INVISIBLE (-6375 3275);
FORCEPROP 1 LAST PATH I305
J 2
(-6048 3400);
DISPLAY 0.872340 (-6048 3400);
PAINT GREEN (-6048 3400);
DISPLAY INVISIBLE (-6048 3400);
FORCEADD TAP..1
R 2
(-6050 3350);
FORCEPROP 3 LASTPIN (-6000 3350) SIG_NAME M_G_CPU0_SB_CA<3>
J 0
(-5990 3360);
DISPLAY 0.659574 (-5990 3360);
PAINT MONO (-5990 3360);
DISPLAY INVISIBLE (-5990 3360);
FORCEPROP 1 LASTPIN (-6000 3350) BN 3
J 2
(-5988 3358);
DISPLAY 0.489362 (-5988 3358);
PAINT GREEN (-5988 3358);
FORCEPROP 2 LAST CDS_LIB mstr_standard
J 0
(-6050 3350);
DISPLAY 0.723404 (-6050 3350);
PAINT MONO (-6050 3350);
DISPLAY INVISIBLE (-6050 3350);
FORCEPROP 1 LAST BODY_TYPE PLUMBING
J 2
(-6050 3400);
DISPLAY 0.872340 (-6050 3400);
PAINT GREEN (-6050 3400);
DISPLAY INVISIBLE (-6050 3400);
FORCEPROP 1 LAST HDL_TAP TRUE
J 2
(-6375 3225);
DISPLAY 0.872340 (-6375 3225);
DISPLAY INVISIBLE (-6375 3225);
FORCEPROP 1 LAST PATH I306
J 2
(-6048 3350);
DISPLAY 0.872340 (-6048 3350);
PAINT GREEN (-6048 3350);
DISPLAY INVISIBLE (-6048 3350);
FORCEADD TAP..1
R 2
(-6050 3300);
FORCEPROP 3 LASTPIN (-6000 3300) SIG_NAME M_G_CPU0_SB_CA<4>
J 0
(-5990 3310);
DISPLAY 0.659574 (-5990 3310);
PAINT MONO (-5990 3310);
DISPLAY INVISIBLE (-5990 3310);
FORCEPROP 1 LASTPIN (-6000 3300) BN 4
J 2
(-5988 3308);
DISPLAY 0.489362 (-5988 3308);
PAINT GREEN (-5988 3308);
FORCEPROP 2 LAST CDS_LIB mstr_standard
J 0
(-6050 3300);
DISPLAY 0.723404 (-6050 3300);
PAINT MONO (-6050 3300);
DISPLAY INVISIBLE (-6050 3300);
FORCEPROP 1 LAST BODY_TYPE PLUMBING
J 2
(-6050 3350);
DISPLAY 0.872340 (-6050 3350);
PAINT GREEN (-6050 3350);
DISPLAY INVISIBLE (-6050 3350);
FORCEPROP 1 LAST HDL_TAP TRUE
J 2
(-6375 3175);
DISPLAY 0.872340 (-6375 3175);
DISPLAY INVISIBLE (-6375 3175);
FORCEPROP 1 LAST PATH I307
J 2
(-6048 3300);
DISPLAY 0.872340 (-6048 3300);
PAINT GREEN (-6048 3300);
DISPLAY INVISIBLE (-6048 3300);
FORCEADD TAP..1
R 2
(-6050 3250);
FORCEPROP 3 LASTPIN (-6000 3250) SIG_NAME M_G_CPU0_SB_CA<5>
J 0
(-5990 3260);
DISPLAY 0.659574 (-5990 3260);
PAINT MONO (-5990 3260);
DISPLAY INVISIBLE (-5990 3260);
FORCEPROP 1 LASTPIN (-6000 3250) BN 5
J 2
(-5988 3258);
DISPLAY 0.489362 (-5988 3258);
PAINT GREEN (-5988 3258);
FORCEPROP 2 LAST CDS_LIB mstr_standard
J 0
(-6050 3250);
DISPLAY 0.723404 (-6050 3250);
PAINT MONO (-6050 3250);
DISPLAY INVISIBLE (-6050 3250);
FORCEPROP 1 LAST BODY_TYPE PLUMBING
J 2
(-6050 3300);
DISPLAY 0.872340 (-6050 3300);
PAINT GREEN (-6050 3300);
DISPLAY INVISIBLE (-6050 3300);
FORCEPROP 1 LAST HDL_TAP TRUE
J 2
(-6375 3125);
DISPLAY 0.872340 (-6375 3125);
DISPLAY INVISIBLE (-6375 3125);
FORCEPROP 1 LAST PATH I308
J 2
(-6048 3250);
DISPLAY 0.872340 (-6048 3250);
PAINT GREEN (-6048 3250);
DISPLAY INVISIBLE (-6048 3250);
FORCEADD TAP..1
R 2
(-6050 3200);
FORCEPROP 3 LASTPIN (-6000 3200) SIG_NAME M_G_CPU0_SB_CA<6>
J 0
(-5990 3210);
DISPLAY 0.659574 (-5990 3210);
PAINT MONO (-5990 3210);
DISPLAY INVISIBLE (-5990 3210);
FORCEPROP 1 LASTPIN (-6000 3200) BN 6
J 2
(-5988 3208);
DISPLAY 0.489362 (-5988 3208);
PAINT GREEN (-5988 3208);
FORCEPROP 2 LAST CDS_LIB mstr_standard
J 0
(-6050 3200);
DISPLAY 0.723404 (-6050 3200);
PAINT MONO (-6050 3200);
DISPLAY INVISIBLE (-6050 3200);
FORCEPROP 1 LAST BODY_TYPE PLUMBING
J 2
(-6050 3250);
DISPLAY 0.872340 (-6050 3250);
PAINT GREEN (-6050 3250);
DISPLAY INVISIBLE (-6050 3250);
FORCEPROP 1 LAST HDL_TAP TRUE
J 2
(-6375 3075);
DISPLAY 0.872340 (-6375 3075);
DISPLAY INVISIBLE (-6375 3075);
FORCEPROP 1 LAST PATH I309
J 2
(-6048 3200);
DISPLAY 0.872340 (-6048 3200);
PAINT GREEN (-6048 3200);
DISPLAY INVISIBLE (-6048 3200);
FORCEADD OFFPAGE..2
R 2
(-6650 3925);
FORCEPROP 2 LAST $XR0 91 
J 0
(-6874 3925);
DISPLAY 0.638298 (-6874 3925);
PAINT MONO (-6874 3925);
FORCEPROP 2 LAST PATH I310
J 0
(-6900 3975);
DISPLAY 1.021277 (-6900 3975);
DISPLAY INVISIBLE (-6900 3975);
FORCEPROP 1 LAST COMMENT_BODY TRUE
J 2
(-6605 3830);
DISPLAY 0.872340 (-6605 3830);
PAINT GREEN (-6605 3830);
DISPLAY INVISIBLE (-6605 3830);
FORCEPROP 1 LAST OFFPAGE TRUE
J 2
(-6975 3800);
DISPLAY 0.872340 (-6975 3800);
PAINT GREEN (-6975 3800);
DISPLAY INVISIBLE (-6975 3800);
FORCEPROP 2 LAST CDS_LIB standard
J 0
(-6650 3925);
DISPLAY INVISIBLE (-6650 3925);
FORCEADD OFFPAGE..2
R 2
(-6650 3525);
FORCEPROP 2 LAST $XR0 91 
J 0
(-6874 3525);
DISPLAY 0.638298 (-6874 3525);
PAINT MONO (-6874 3525);
FORCEPROP 2 LAST PATH I311
J 0
(-6900 3575);
DISPLAY 1.021277 (-6900 3575);
DISPLAY INVISIBLE (-6900 3575);
FORCEPROP 1 LAST COMMENT_BODY TRUE
J 2
(-6605 3430);
DISPLAY 0.872340 (-6605 3430);
PAINT GREEN (-6605 3430);
DISPLAY INVISIBLE (-6605 3430);
FORCEPROP 1 LAST OFFPAGE TRUE
J 2
(-6975 3400);
DISPLAY 0.872340 (-6975 3400);
PAINT GREEN (-6975 3400);
DISPLAY INVISIBLE (-6975 3400);
FORCEPROP 2 LAST CDS_LIB standard
J 0
(-6650 3525);
DISPLAY INVISIBLE (-6650 3525);
FORCEADD OFFPAGE..2
R 2
(-6650 3000);
FORCEPROP 2 LAST $XR0 91 
J 0
(-6874 3000);
DISPLAY 0.638298 (-6874 3000);
PAINT MONO (-6874 3000);
FORCEPROP 2 LAST PATH I312
J 0
(-6900 3050);
DISPLAY 1.021277 (-6900 3050);
DISPLAY INVISIBLE (-6900 3050);
FORCEPROP 1 LAST COMMENT_BODY TRUE
J 2
(-6605 2905);
DISPLAY 0.872340 (-6605 2905);
PAINT GREEN (-6605 2905);
DISPLAY INVISIBLE (-6605 2905);
FORCEPROP 1 LAST OFFPAGE TRUE
J 2
(-6975 2875);
DISPLAY 0.872340 (-6975 2875);
PAINT GREEN (-6975 2875);
DISPLAY INVISIBLE (-6975 2875);
FORCEPROP 2 LAST CDS_LIB standard
J 0
(-6650 3000);
DISPLAY INVISIBLE (-6650 3000);
FORCEADD OFFPAGE..2
R 2
(-6650 3050);
FORCEPROP 2 LAST $XR0 91 
J 0
(-6874 3050);
DISPLAY 0.638298 (-6874 3050);
PAINT MONO (-6874 3050);
FORCEPROP 2 LAST PATH I313
J 0
(-6900 3100);
DISPLAY 1.021277 (-6900 3100);
DISPLAY INVISIBLE (-6900 3100);
FORCEPROP 1 LAST COMMENT_BODY TRUE
J 2
(-6605 2955);
DISPLAY 0.872340 (-6605 2955);
PAINT GREEN (-6605 2955);
DISPLAY INVISIBLE (-6605 2955);
FORCEPROP 1 LAST OFFPAGE TRUE
J 2
(-6975 2925);
DISPLAY 0.872340 (-6975 2925);
PAINT GREEN (-6975 2925);
DISPLAY INVISIBLE (-6975 2925);
FORCEPROP 2 LAST CDS_LIB standard
J 0
(-6650 3050);
DISPLAY INVISIBLE (-6650 3050);
FORCEADD OFFPAGE..2
R 2
(-6650 2850);
FORCEPROP 2 LAST $XR0 91 
J 0
(-6874 2850);
DISPLAY 0.638298 (-6874 2850);
PAINT MONO (-6874 2850);
FORCEPROP 2 LAST PATH I314
J 0
(-6900 2900);
DISPLAY 1.021277 (-6900 2900);
DISPLAY INVISIBLE (-6900 2900);
FORCEPROP 1 LAST COMMENT_BODY TRUE
J 2
(-6605 2755);
DISPLAY 0.872340 (-6605 2755);
PAINT GREEN (-6605 2755);
DISPLAY INVISIBLE (-6605 2755);
FORCEPROP 1 LAST OFFPAGE TRUE
J 2
(-6975 2725);
DISPLAY 0.872340 (-6975 2725);
PAINT GREEN (-6975 2725);
DISPLAY INVISIBLE (-6975 2725);
FORCEPROP 2 LAST CDS_LIB standard
J 0
(-6650 2850);
DISPLAY INVISIBLE (-6650 2850);
FORCEADD OFFPAGE..2
R 2
(-6650 2900);
FORCEPROP 2 LAST $XR0 91 
J 0
(-6874 2900);
DISPLAY 0.638298 (-6874 2900);
PAINT MONO (-6874 2900);
FORCEPROP 2 LAST PATH I315
J 0
(-6900 2950);
DISPLAY 1.021277 (-6900 2950);
DISPLAY INVISIBLE (-6900 2950);
FORCEPROP 1 LAST COMMENT_BODY TRUE
J 2
(-6605 2805);
DISPLAY 0.872340 (-6605 2805);
PAINT GREEN (-6605 2805);
DISPLAY INVISIBLE (-6605 2805);
FORCEPROP 1 LAST OFFPAGE TRUE
J 2
(-6975 2775);
DISPLAY 0.872340 (-6975 2775);
PAINT GREEN (-6975 2775);
DISPLAY INVISIBLE (-6975 2775);
FORCEPROP 2 LAST CDS_LIB standard
J 0
(-6650 2900);
DISPLAY INVISIBLE (-6650 2900);
FORCEADD OFFPAGE..5
(-6650 2650);
FORCEPROP 2 LAST $XR0 91 
J 0
(-6874 2650);
DISPLAY 0.638298 (-6874 2650);
PAINT MONO (-6874 2650);
FORCEPROP 2 LAST PATH I316
J 0
(-6900 2700);
DISPLAY 1.021277 (-6900 2700);
DISPLAY INVISIBLE (-6900 2700);
FORCEPROP 1 LAST COMMENT_BODY TRUE
J 0
(-6550 2575);
DISPLAY 0.872340 (-6550 2575);
PAINT GREEN (-6550 2575);
DISPLAY INVISIBLE (-6550 2575);
FORCEPROP 1 LAST OFFPAGE TRUE
J 0
(-6325 2525);
DISPLAY 0.872340 (-6325 2525);
PAINT GREEN (-6325 2525);
DISPLAY INVISIBLE (-6325 2525);
FORCEPROP 2 LAST CDS_LIB mstr_standard
J 0
(-6650 2650);
DISPLAY INVISIBLE (-6650 2650);
FORCEADD OFFPAGE..1
(-6650 2750);
FORCEPROP 2 LAST $XR0 91 
J 0
(-6901 2750);
DISPLAY 0.638298 (-6901 2750);
PAINT MONO (-6901 2750);
FORCEPROP 2 LAST PATH I317
J 0
(-6925 2800);
DISPLAY 1.021277 (-6925 2800);
DISPLAY INVISIBLE (-6925 2800);
FORCEPROP 1 LAST COMMENT_BODY TRUE
J 0
(-6525 2650);
DISPLAY 0.872340 (-6525 2650);
PAINT GREEN (-6525 2650);
DISPLAY INVISIBLE (-6525 2650);
FORCEPROP 1 LAST OFFPAGE TRUE
J 0
(-6325 2625);
DISPLAY 0.872340 (-6325 2625);
PAINT GREEN (-6325 2625);
DISPLAY INVISIBLE (-6325 2625);
FORCEPROP 2 LAST CDS_LIB standard
J 0
(-6650 2750);
DISPLAY INVISIBLE (-6650 2750);
FORCEADD OFFPAGE..1
(-6650 2400);
FORCEPROP 2 LAST $XR0 91 
J 0
(-6901 2400);
DISPLAY 0.638298 (-6901 2400);
PAINT MONO (-6901 2400);
FORCEPROP 2 LAST PATH I318
J 0
(-6925 2450);
DISPLAY 1.021277 (-6925 2450);
DISPLAY INVISIBLE (-6925 2450);
FORCEPROP 1 LAST COMMENT_BODY TRUE
J 0
(-6525 2300);
DISPLAY 0.872340 (-6525 2300);
PAINT GREEN (-6525 2300);
DISPLAY INVISIBLE (-6525 2300);
FORCEPROP 1 LAST OFFPAGE TRUE
J 0
(-6325 2275);
DISPLAY 0.872340 (-6325 2275);
PAINT GREEN (-6325 2275);
DISPLAY INVISIBLE (-6325 2275);
FORCEPROP 2 LAST CDS_LIB standard
J 0
(-6650 2400);
DISPLAY INVISIBLE (-6650 2400);
FORCEADD OFFPAGE..2
R 2
(-6650 2550);
FORCEPROP 2 LAST $XR0 91 
J 0
(-6874 2550);
DISPLAY 0.638298 (-6874 2550);
PAINT MONO (-6874 2550);
FORCEPROP 2 LAST PATH I319
J 0
(-6900 2600);
DISPLAY 1.021277 (-6900 2600);
DISPLAY INVISIBLE (-6900 2600);
FORCEPROP 1 LAST COMMENT_BODY TRUE
J 2
(-6605 2455);
DISPLAY 0.872340 (-6605 2455);
PAINT GREEN (-6605 2455);
DISPLAY INVISIBLE (-6605 2455);
FORCEPROP 1 LAST OFFPAGE TRUE
J 2
(-6975 2425);
DISPLAY 0.872340 (-6975 2425);
PAINT GREEN (-6975 2425);
DISPLAY INVISIBLE (-6975 2425);
FORCEPROP 2 LAST CDS_LIB standard
J 0
(-6650 2550);
DISPLAY INVISIBLE (-6650 2550);
FORCEADD OFFPAGE..2
R 2
(-6650 2500);
FORCEPROP 2 LAST $XR0 91 
J 0
(-6874 2500);
DISPLAY 0.638298 (-6874 2500);
PAINT MONO (-6874 2500);
FORCEPROP 2 LAST PATH I320
J 0
(-6900 2550);
DISPLAY 1.021277 (-6900 2550);
DISPLAY INVISIBLE (-6900 2550);
FORCEPROP 1 LAST COMMENT_BODY TRUE
J 2
(-6605 2405);
DISPLAY 0.872340 (-6605 2405);
PAINT GREEN (-6605 2405);
DISPLAY INVISIBLE (-6605 2405);
FORCEPROP 1 LAST OFFPAGE TRUE
J 2
(-6975 2375);
DISPLAY 0.872340 (-6975 2375);
PAINT GREEN (-6975 2375);
DISPLAY INVISIBLE (-6975 2375);
FORCEPROP 2 LAST CDS_LIB standard
J 0
(-6650 2500);
DISPLAY INVISIBLE (-6650 2500);
FORCEADD OFFPAGE..5
(-6650 2300);
FORCEPROP 2 LAST $XR0 91 
J 0
(-6874 2300);
DISPLAY 0.638298 (-6874 2300);
PAINT MONO (-6874 2300);
FORCEPROP 2 LAST PATH I321
J 0
(-6900 2350);
DISPLAY 1.021277 (-6900 2350);
DISPLAY INVISIBLE (-6900 2350);
FORCEPROP 1 LAST COMMENT_BODY TRUE
J 0
(-6550 2225);
DISPLAY 0.872340 (-6550 2225);
PAINT GREEN (-6550 2225);
DISPLAY INVISIBLE (-6550 2225);
FORCEPROP 1 LAST OFFPAGE TRUE
J 0
(-6325 2175);
DISPLAY 0.872340 (-6325 2175);
PAINT GREEN (-6325 2175);
DISPLAY INVISIBLE (-6325 2175);
FORCEPROP 2 LAST CDS_LIB standard
J 0
(-6650 2300);
DISPLAY INVISIBLE (-6650 2300);
FORCEADD OFFPAGE..5
(-6650 2100);
FORCEPROP 2 LAST $XR0 91 
J 0
(-6874 2100);
DISPLAY 0.638298 (-6874 2100);
PAINT MONO (-6874 2100);
FORCEPROP 2 LAST PATH I322
J 0
(-6900 2150);
DISPLAY 1.021277 (-6900 2150);
DISPLAY INVISIBLE (-6900 2150);
FORCEPROP 1 LAST COMMENT_BODY TRUE
J 0
(-6550 2025);
DISPLAY 0.872340 (-6550 2025);
PAINT GREEN (-6550 2025);
DISPLAY INVISIBLE (-6550 2025);
FORCEPROP 1 LAST OFFPAGE TRUE
J 0
(-6325 1975);
DISPLAY 0.872340 (-6325 1975);
PAINT GREEN (-6325 1975);
DISPLAY INVISIBLE (-6325 1975);
FORCEPROP 2 LAST CDS_LIB standard
J 0
(-6650 2100);
DISPLAY INVISIBLE (-6650 2100);
FORCEADD Q_RES..1
(-6975 2200);
FORCEPROP 1 LAST LOCATION R381
J 0
(-7300 2200);
DISPLAY 0.489362 (-7300 2200);
PAINT SKYBLUE (-7300 2200);
FORCEPROP 0 LAST $SEC 1
J 0
(-7150 2250);
DISPLAY 0.680851 (-7150 2250);
PAINT MONO (-7150 2250);
DISPLAY INVISIBLE (-7150 2250);
FORCEPROP 0 LAST CDS_SEC 1
J 0
(-7150 2250);
DISPLAY 1.021277 (-7150 2250);
DISPLAY INVISIBLE (-7150 2250);
FORCEPROP 1 LASTPIN (-7075 2200) $PN 1
J 0
(-7063 2212);
DISPLAY 0.489362 (-7063 2212);
PAINT MONO (-7063 2212);
FORCEPROP 1 LASTPIN (-6875 2200) $PN 2
J 0
(-6913 2212);
DISPLAY 0.489362 (-6913 2212);
PAINT MONO (-6913 2212);
FORCEPROP 1 LAST TOLERANCE 1%
J 0
(-6700 2200);
DISPLAY 0.489362 (-6700 2200);
PAINT SKYBLUE (-6700 2200);
FORCEPROP 1 LAST VALUE 15   
J 2
(-6650 2200);
DISPLAY 0.489362 (-6650 2200);
PAINT SKYBLUE (-6650 2200);
FORCEPROP 1 LAST PART_NUMBER CS01502FB11
J 0
(-6875 2175);
DISPLAY 0.489362 (-6875 2175);
PAINT SKYBLUE (-6875 2175);
FORCEPROP 1 LAST PACK_TYPE 0402LF
J 0
(-7300 2175);
DISPLAY 0.489362 (-7300 2175);
PAINT SKYBLUE (-7300 2175);
FORCEPROP 2 LAST CDS_LIB pure_quanta
J 0
(-6975 2200);
DISPLAY INVISIBLE (-6975 2200);
FORCEPROP 1 LAST PATH I323
J 0
(-7025 2350);
DISPLAY 0.978723 (-7025 2350);
PAINT WHITE (-7025 2350);
DISPLAY INVISIBLE (-7025 2350);
FORCEPROP 1 LAST WATTAGE 1/16W
J 2
(-6750 2325);
DISPLAY 0.638298 (-6750 2325);
PAINT SKYBLUE (-6750 2325);
DISPLAY INVISIBLE (-6750 2325);
FORCEPROP 1 LAST MATERIAL CHIP
J 0
(-7100 2325);
DISPLAY 0.638298 (-7100 2325);
PAINT SKYBLUE (-7100 2325);
DISPLAY INVISIBLE (-7100 2325);
FORCEADD OFFPAGE..1
(-7850 2200);
FORCEPROP 2 LAST $XR0 91 
J 0
(-8071 2200);
DISPLAY 0.638298 (-8071 2200);
PAINT MONO (-8071 2200);
FORCEPROP 2 LAST PATH I324
J 0
(-8100 2250);
DISPLAY 1.021277 (-8100 2250);
DISPLAY INVISIBLE (-8100 2250);
FORCEPROP 1 LAST COMMENT_BODY TRUE
J 0
(-7725 2100);
DISPLAY 0.872340 (-7725 2100);
PAINT GREEN (-7725 2100);
DISPLAY INVISIBLE (-7725 2100);
FORCEPROP 1 LAST OFFPAGE TRUE
J 0
(-7525 2075);
DISPLAY 0.872340 (-7525 2075);
PAINT GREEN (-7525 2075);
DISPLAY INVISIBLE (-7525 2075);
FORCEPROP 2 LAST CDS_LIB mstr_standard
J 0
(-7850 2200);
DISPLAY INVISIBLE (-7850 2200);
FORCEADD CAD_NOTE..1
(-7850 2500);
FORCEPROP 0 LAST L1 R1955 PLACE CLOSE TO CPU < 25MM
J 0
(-8000 2375);
DISPLAY 0.617021 (-8000 2375);
PAINT WHITE (-8000 2375);
FORCEPROP 2 LAST CDS_LIB pure_quanta_power
J 0
(-7850 2500);
DISPLAY INVISIBLE (-7850 2500);
FORCEPROP 1 LAST COMMENT_BODY TRUE
J 0
(-7825 2600);
DISPLAY 0.574468 (-7825 2600);
PAINT WHITE (-7825 2600);
DISPLAY INVISIBLE (-7825 2600);
FORCEADD QUANTA_TITLE_BLOCK_C..1
(-100 100);
FORCEPROP 0 LAST CDS_CON_LAST_MODIFIED Fri Mar 11 14:52:14 2022
J 0
(-1985 115);
DISPLAY INVISIBLE (-1985 115);
FORCEPROP 1 LAST CUSTOM_TXT_CDS <CON_LAST_MODIFIED>
J 0
(-1985 115);
DISPLAY 0.978723 (-1985 115);
FORCEPROP 2 LAST CUSTOM_TXT_CDS <XR_PAGE_TITLE>
J 0
(-7990 5350);
DISPLAY 0.638298 (-7990 5350);
PAINT PINK (-7990 5350);
DISPLAY INVISIBLE (-7990 5350);
FORCEPROP 1 LAST CUSTOM_TXT_CDS <NAME_2>
J 0
(-3275 150);
FORCEPROP 1 LAST CUSTOM_TXT_CDS <NAME_1>
J 0
(-3275 275);
FORCEPROP 1 LAST CUSTOM_TXT_CDS <Q_NUMBER>
J 0
(-1503 203);
DISPLAY 1.212766 (-1503 203);
FORCEPROP 1 LAST CUSTOM_TXT_CDS <Q_PROJ>
J 0
(-2482 202);
DISPLAY 1.212766 (-2482 202);
FORCEPROP 1 LAST CUSTOM_TXT_CDS <Q_REV>
J 0
(-284 203);
DISPLAY 1.212766 (-284 203);
FORCEPROP 1 LAST CUSTOM_TXT_CDS <CON_PAGE_NUM> OF <CON_TOTAL_PAGES>
J 0
(-546 118);
DISPLAY 0.978723 (-546 118);
FORCEPROP 1 LAST Q_TITLE CPU0 DDR CHG
J 0
(-9375 150);
DISPLAY 2.446809 (-9375 150);
PAINT GREEN (-9375 150);
FORCEPROP 1 LAST Q_DEPT BU9
J 1
(-3863 149);
DISPLAY 1.957447 (-3863 149);
PAINT GREEN (-3863 149);
FORCEPROP 1 LAST CDS_LMAN_SYM_OUTLINE -9475,6775,100,-125
J 0
(-100 100);
DISPLAY 0.468085 (-100 100);
PAINT GREEN (-100 100);
DISPLAY INVISIBLE (-100 100);
FORCEPROP 2 LAST CDS_LIB pure_quanta
J 0
(-100 100);
DISPLAY INVISIBLE (-100 100);
FORCEPROP 2 LAST PAGE_BORDER TRUE
J 0
(-7990 5350);
DISPLAY 0.638298 (-7990 5350);
PAINT PINK (-7990 5350);
DISPLAY INVISIBLE (-7990 5350);
FORCEPROP 1 LAST COMMENT_BODY TRUE
J 0
(-88 87);
DISPLAY 0.978723 (-88 87);
PAINT GREEN (-88 87);
DISPLAY INVISIBLE (-88 87);
FORCEPROP 2 LAST CDS_XR_PAGE_TITLE CR-16 : @T6G_MB_LIB.T6G(SCH_1):PAGE16
J 0
(-7990 5350);
DISPLAY 0.638298 (-7990 5350);
PAINT PINK (-7990 5350);
DISPLAY INVISIBLE (-7990 5350);
WIRE 17 -1 (-3375 5475)(-3375 5425);
WIRE 17 -1 (-3375 5525)(-3375 5475);
WIRE 17 -1 (-3375 5425)(-3375 5375);
WIRE 17 -1 (-3375 5375)(-3375 5325);
WIRE 17 -1 (-3375 5575)(-3375 5525);
WIRE 17 -1 (-3375 5625)(-3375 5575);
WIRE 17 -1 (-3375 5325)(-3375 5275);
WIRE 17 -1 (-3375 5175)(-3375 5275);
WIRE 17 -1 (-3375 5725)(-3375 5625);
WIRE 17 -1 (-3375 5775)(-3375 5725);
WIRE 17 -1 (-3375 5125)(-3375 5175);
WIRE 17 -1 (-3375 5075)(-3375 5125);
WIRE 17 -1 (-3375 5825)(-3375 5775);
WIRE 17 -1 (-3375 5875)(-3375 5825);
WIRE 17 -1 (-3375 5025)(-3375 5075);
WIRE 17 -1 (-3375 5025)(-3375 4975);
WIRE 17 -1 (-3375 5925)(-3375 5875);
WIRE 17 -1 (-3375 5975)(-3375 5925);
WIRE 17 -1 (-3375 4975)(-3375 4925);
WIRE 17 -1 (-3375 4925)(-3375 4875);
WIRE 17 -1 (-3375 6025)(-3375 5975);
WIRE 17 -1 (-3375 6075)(-3375 6025);
WIRE 17 -1 (-3375 4875)(-3375 4825);
WIRE 17 -1 (-3375 4825)(-3375 4725);
WIRE 17 -1 (-3375 6075)(-2750 6075);
FORCEPROP 2 LAST SIG_NAME M_G_CPU0_SA_DQ<31:0>
J 2
(-2810 6085);
DISPLAY 0.489362 (-2810 6085);
WIRE 17 -1 (-3375 4725)(-3375 4675);
WIRE 17 -1 (-3375 4675)(-3375 4625);
WIRE 17 -1 (-3375 4625)(-3375 4575);
WIRE 17 -1 (-3375 4525)(-3375 4575);
WIRE 17 -1 (-3375 4475)(-3375 4525);
WIRE 17 -1 (-3375 4425)(-3375 4475);
WIRE 17 -1 (-3375 4375)(-3375 4425);
WIRE 17 -1 (-3375 4225)(-3375 4175);
WIRE 17 -1 (-3375 4275)(-3375 4225);
WIRE 17 -1 (-3375 4175)(-3375 4125);
WIRE 17 -1 (-3375 4125)(-3375 4075);
WIRE 17 -1 (-3375 4275)(-2750 4275);
FORCEPROP 2 LAST SIG_NAME M_G_CPU0_SB_DQ<31:0>
J 2
(-2810 4285);
DISPLAY 0.489362 (-2810 4285);
WIRE 17 -1 (-3375 4075)(-3375 4025);
WIRE 17 -1 (-3375 4025)(-3375 3975);
WIRE 17 -1 (-3375 3975)(-3375 3925);
WIRE 17 -1 (-3375 3925)(-3375 3825);
WIRE 17 -1 (-3375 3825)(-3375 3775);
WIRE 17 -1 (-3375 3175)(-3375 3125);
WIRE 17 -1 (-3375 3225)(-3375 3175);
WIRE 17 -1 (-3375 3125)(-3375 3075);
WIRE 17 -1 (-3375 3075)(-3375 3025);
WIRE 17 -1 (-3375 3225)(-3375 3275);
WIRE 17 -1 (-3375 3275)(-3375 3325);
WIRE 17 -1 (-3375 3025)(-3375 2925);
WIRE 17 -1 (-3375 2925)(-3375 2875);
WIRE 17 -1 (-3375 3325)(-3375 3375);
WIRE 17 -1 (-3375 3375)(-3375 3475);
WIRE 17 -1 (-3375 2875)(-3375 2825);
WIRE 17 -1 (-3375 2825)(-3375 2775);
WIRE 17 -1 (-3375 3525)(-3375 3475);
WIRE 17 -1 (-3375 3575)(-3375 3525);
WIRE 17 -1 (-3375 2725)(-3375 2775);
WIRE 17 -1 (-3375 2675)(-3375 2725);
WIRE 17 -1 (-3375 3625)(-3375 3575);
WIRE 17 -1 (-3375 3675)(-3375 3625);
WIRE 17 -1 (-3375 2625)(-3375 2675);
WIRE 17 -1 (-3375 2575)(-3375 2625);
WIRE 17 -1 (-3375 3725)(-3375 3675);
WIRE 17 -1 (-3375 3775)(-3375 3725);
WIRE 17 -1 (-3375 2375)(-3375 2425);
WIRE 17 -1 (-3375 2375)(-3375 2325);
WIRE 17 -1 (-3375 2475)(-3375 2425);
WIRE 17 -1 (-3375 2475)(-3375 2500);
WIRE 17 -1 (-3375 2275)(-3375 2325);
WIRE 17 -1 (-3375 2225)(-3375 2275);
WIRE 17 -1 (-3375 2500)(-2875 2500);
FORCEPROP 2 LAST SIG_NAME M_G_CPU0_SA_CB<7:0>
J 2
(-2875 2510);
DISPLAY 0.489362 (-2875 2510);
WIRE 17 -1 (-3375 2175)(-3375 2225);
WIRE 17 -1 (-3375 2125)(-3375 2175);
WIRE 17 -1 (-3375 2025)(-3375 1975);
WIRE 17 -1 (-3375 2025)(-3375 2050);
WIRE 17 -1 (-3375 1925)(-3375 1975);
WIRE 17 -1 (-3375 1925)(-3375 1875);
WIRE 17 -1 (-3375 2050)(-2875 2050);
FORCEPROP 2 LAST SIG_NAME M_G_CPU0_SB_CB<7:0>
J 2
(-2875 2060);
DISPLAY 0.489362 (-2875 2060);
WIRE 17 -1 (-3375 1825)(-3375 1875);
WIRE 17 -1 (-3375 1775)(-3375 1825);
WIRE 17 -1 (-3375 1725)(-3375 1775);
WIRE 17 -1 (-3375 1675)(-3375 1725);
WIRE 17 -1 (-6100 6025)(-6100 5925);
FORCEPROP 2 LAST SIG_NAME M_G_CPU0_SA_DQS_DN<9:0>
J 2
(-6135 6035);
DISPLAY 0.489362 (-6135 6035);
WIRE 17 -1 (-6100 5825)(-6100 5725);
WIRE 17 -1 (-6100 5925)(-6100 5825);
WIRE 17 -1 (-6100 5725)(-6100 5625);
WIRE 17 -1 (-6100 5525)(-6100 5625);
WIRE 17 -1 (-6100 5425)(-6100 5525);
WIRE 17 -1 (-6100 5325)(-6100 5425);
WIRE 17 -1 (-6100 5325)(-6100 5225);
WIRE 17 -1 (-5900 6075)(-5900 5975);
WIRE 17 -1 (-5900 6075)(-6700 6075);
FORCEPROP 2 LAST SIG_NAME M_G_CPU0_SA_DQS_DP<9:0>
J 2
(-6135 6085);
DISPLAY 0.489362 (-6135 6085);
WIRE 17 -1 (-6100 5225)(-6100 5125);
WIRE 17 -1 (-5900 5975)(-5900 5875);
WIRE 17 -1 (-5900 5875)(-5900 5775);
WIRE 17 -1 (-5900 5775)(-5900 5675);
WIRE 17 -1 (-5900 5575)(-5900 5675);
WIRE 17 -1 (-5900 5475)(-5900 5575);
WIRE 17 -1 (-5900 5375)(-5900 5475);
WIRE 17 -1 (-5900 5375)(-5900 5275);
WIRE 17 -1 (-5900 5275)(-5900 5175);
WIRE 17 -1 (-5900 4525)(-5900 4625);
WIRE 17 -1 (-5900 4425)(-5900 4525);
WIRE 17 -1 (-5900 4725)(-5900 4625);
WIRE 17 -1 (-5900 4825)(-5900 4725);
WIRE 17 -1 (-5900 4325)(-5900 4425);
WIRE 17 -1 (-5900 4325)(-5900 4225);
WIRE 17 -1 (-5900 4925)(-5900 4825);
WIRE 17 -1 (-5900 5025)(-5900 4925);
WIRE 17 -1 (-5900 4225)(-5900 4125);
WIRE 17 -1 (-5900 5025)(-6700 5025);
FORCEPROP 2 LAST SIG_NAME M_G_CPU0_SB_DQS_DP<9:0>
J 2
(-6135 5035);
DISPLAY 0.489362 (-6135 5035);
WIRE 17 -1 (-6100 4975)(-6100 4875);
FORCEPROP 2 LAST SIG_NAME M_G_CPU0_SB_DQS_DN<9:0>
J 2
(-6135 4985);
DISPLAY 0.489362 (-6135 4985);
WIRE 17 -1 (-6100 4775)(-6100 4675);
WIRE 17 -1 (-6100 4875)(-6100 4775);
WIRE 17 -1 (-6100 4675)(-6100 4575);
WIRE 17 -1 (-6100 4475)(-6100 4575);
WIRE 17 -1 (-6100 4375)(-6100 4475);
WIRE 17 -1 (-6100 4275)(-6100 4375);
WIRE 17 -1 (-6100 4275)(-6100 4175);
WIRE 17 -1 (-6100 4175)(-6100 4075);
WIRE 17 -1 (-6100 3875)(-6100 3925);
WIRE 17 -1 (-6100 3825)(-6100 3875);
WIRE 17 -1 (-6100 3925)(-6600 3925);
FORCEPROP 2 LAST SIG_NAME M_G_CPU0_SA_CA<6:0>
J 0
(-6600 3935);
DISPLAY 0.489362 (-6600 3935);
WIRE 17 -1 (-6100 3475)(-6100 3525);
WIRE 17 -1 (-6100 3425)(-6100 3475);
WIRE 17 -1 (-6100 3525)(-6600 3525);
FORCEPROP 2 LAST SIG_NAME M_G_CPU0_SB_CA<6:0>
J 0
(-6600 3535);
DISPLAY 0.489362 (-6600 3535);
WIRE 17 -1 (-6100 3775)(-6100 3825);
WIRE 17 -1 (-6100 3375)(-6100 3425);
WIRE 17 -1 (-6100 3725)(-6100 3775);
WIRE 17 -1 (-6100 3675)(-6100 3725);
WIRE 17 -1 (-6100 3625)(-6100 3675);
WIRE 17 -1 (-6100 3325)(-6100 3375);
WIRE 17 -1 (-6100 3275)(-6100 3325);
WIRE 17 -1 (-6100 3225)(-6100 3275);
WIRE 17 -1 (-6100 6025)(-6700 6025);
WIRE 17 -1 (-6100 4975)(-6700 4975);
WIRE 16 -1 (-7800 2200)(-7075 2200);
FORCEPROP 2 LAST SIG_NAME M_G_CPU0_ALERT_N
J 0
(-7760 2210);
DISPLAY 0.489362 (-7760 2210);
WIRE 16 -1 (-6600 1250)(-5500 1250);
FORCEPROP 2 LAST SIG_NAME TP_M_G_CPU0_SA_TEST39G
J 0
(-6585 1260);
DISPLAY 0.489362 (-6585 1260);
FORCEPROP 2 LASTPROP $XRERR UNIQUE?
J 0
(-6840 1250);
DISPLAY 0.638298 (-6840 1250);
PAINT MONO (-6840 1250);
DISPLAY INVISIBLE (-6840 1250);
WIRE 16 -1 (-6875 2200)(-5500 2200);
FORCEPROP 2 LAST SIG_NAME M_G_CPU0_ALERT_R_N
J 0
(-6585 2210);
DISPLAY 0.489362 (-6585 2210);
FORCEPROP 2 LASTPROP $XRERR UNIQUE?
J 0
(-6825 2210);
DISPLAY 0.638298 (-6825 2210);
PAINT MONO (-6825 2210);
DISPLAY INVISIBLE (-6825 2210);
WIRE 16 -1 (-6600 3000)(-5500 3000);
FORCEPROP 2 LAST SIG_NAME M_G_CPU0_CLK_DN<0>
J 0
(-6600 3010);
DISPLAY 0.489362 (-6600 3010);
WIRE 16 -1 (-6600 3050)(-5500 3050);
FORCEPROP 2 LAST SIG_NAME M_G_CPU0_CLK_DP<0>
J 0
(-6600 3060);
DISPLAY 0.489362 (-6600 3060);
WIRE 16 -1 (-6600 2850)(-5500 2850);
FORCEPROP 2 LAST SIG_NAME M_G_CPU0_SA_CS_N<1>
J 0
(-6600 2860);
DISPLAY 0.489362 (-6600 2860);
WIRE 16 -1 (-6600 2900)(-5500 2900);
FORCEPROP 2 LAST SIG_NAME M_G_CPU0_SA_CS_N<0>
J 0
(-6600 2910);
DISPLAY 0.489362 (-6600 2910);
WIRE 16 -1 (-6600 2650)(-5500 2650);
FORCEPROP 2 LAST SIG_NAME M_G_CPU0_SA_PAR
J 0
(-6600 2660);
DISPLAY 0.489362 (-6600 2660);
WIRE 16 -1 (-6600 2750)(-5500 2750);
FORCEPROP 2 LAST SIG_NAME M_G_CPU0_SA_RSP<0>
J 0
(-6600 2760);
DISPLAY 0.489362 (-6600 2760);
WIRE 16 -1 (-6600 2400)(-5500 2400);
FORCEPROP 2 LAST SIG_NAME M_G_CPU0_SB_RSP<0>
J 0
(-6600 2410);
DISPLAY 0.489362 (-6600 2410);
WIRE 16 -1 (-6600 2550)(-5500 2550);
FORCEPROP 2 LAST SIG_NAME M_G_CPU0_SB_CS_N<0>
J 0
(-6600 2560);
DISPLAY 0.489362 (-6600 2560);
WIRE 16 -1 (-6600 2500)(-5500 2500);
FORCEPROP 2 LAST SIG_NAME M_G_CPU0_SB_CS_N<1>
J 0
(-6600 2510);
DISPLAY 0.489362 (-6600 2510);
WIRE 16 -1 (-6600 2300)(-5500 2300);
FORCEPROP 2 LAST SIG_NAME M_G_CPU0_SB_PAR
J 0
(-6600 2310);
DISPLAY 0.489362 (-6600 2310);
WIRE 16 -1 (-6600 2100)(-5500 2100);
FORCEPROP 2 LAST SIG_NAME M_G_CPU0_RESET_N
J 0
(-6600 2110);
DISPLAY 0.489362 (-6600 2110);
WIRE 16 -1 (-6000 3200)(-5500 3200);
WIRE 16 -1 (-6000 3600)(-5500 3600);
WIRE 16 -1 (-6000 3250)(-5500 3250);
WIRE 16 -1 (-6000 3650)(-5500 3650);
WIRE 16 -1 (-6000 3300)(-5500 3300);
WIRE 16 -1 (-6000 3700)(-5500 3700);
WIRE 16 -1 (-6000 3350)(-5500 3350);
WIRE 16 -1 (-6000 3750)(-5500 3750);
WIRE 16 -1 (-6000 3400)(-5500 3400);
WIRE 16 -1 (-6000 3800)(-5500 3800);
WIRE 16 -1 (-6000 3450)(-5500 3450);
WIRE 16 -1 (-6000 3850)(-5500 3850);
WIRE 16 -1 (-6000 3500)(-5500 3500);
WIRE 16 -1 (-6000 3900)(-5500 3900);
WIRE 16 -1 (-6000 4050)(-5500 4050);
WIRE 16 -1 (-5800 4100)(-5500 4100);
WIRE 16 -1 (-5800 4600)(-5500 4600);
WIRE 16 -1 (-6000 4150)(-5500 4150);
WIRE 16 -1 (-5800 4700)(-5500 4700);
WIRE 16 -1 (-6000 4250)(-5500 4250);
WIRE 16 -1 (-5800 4800)(-5500 4800);
WIRE 16 -1 (-6000 4350)(-5500 4350);
WIRE 16 -1 (-5800 4900)(-5500 4900);
WIRE 16 -1 (-6000 4450)(-5500 4450);
WIRE 16 -1 (-5800 5000)(-5500 5000);
WIRE 16 -1 (-6000 4550)(-5500 4550);
WIRE 16 -1 (-6000 5100)(-5500 5100);
WIRE 16 -1 (-6000 4650)(-5500 4650);
WIRE 16 -1 (-6000 4750)(-5500 4750);
WIRE 16 -1 (-6000 4850)(-5500 4850);
WIRE 16 -1 (-6000 4950)(-5500 4950);
WIRE 16 -1 (-5800 4200)(-5500 4200);
WIRE 16 -1 (-5800 4300)(-5500 4300);
WIRE 16 -1 (-5800 4400)(-5500 4400);
WIRE 16 -1 (-5800 4500)(-5500 4500);
WIRE 16 -1 (-5800 5150)(-5500 5150);
WIRE 16 -1 (-5800 5250)(-5500 5250);
WIRE 16 -1 (-5800 5350)(-5500 5350);
WIRE 16 -1 (-5800 5450)(-5500 5450);
WIRE 16 -1 (-5800 5550)(-5500 5550);
WIRE 16 -1 (-5800 5650)(-5500 5650);
WIRE 16 -1 (-6000 5200)(-5500 5200);
WIRE 16 -1 (-5800 5750)(-5500 5750);
WIRE 16 -1 (-6000 5300)(-5500 5300);
WIRE 16 -1 (-5800 5850)(-5500 5850);
WIRE 16 -1 (-6000 5400)(-5500 5400);
WIRE 16 -1 (-5800 5950)(-5500 5950);
WIRE 16 -1 (-6000 5500)(-5500 5500);
WIRE 16 -1 (-5800 6050)(-5500 6050);
WIRE 16 -1 (-6000 5600)(-5500 5600);
WIRE 16 -1 (-6000 5700)(-5500 5700);
WIRE 16 -1 (-6000 5800)(-5500 5800);
WIRE 16 -1 (-6000 5900)(-5500 5900);
WIRE 16 -1 (-6000 6000)(-5500 6000);
WIRE 16 -1 (-3900 1650)(-3475 1650);
WIRE 16 -1 (-3900 1700)(-3475 1700);
WIRE 16 -1 (-3900 1750)(-3475 1750);
WIRE 16 -1 (-3900 1800)(-3475 1800);
WIRE 16 -1 (-3900 1850)(-3475 1850);
WIRE 16 -1 (-3900 1900)(-3475 1900);
WIRE 16 -1 (-3900 1950)(-3475 1950);
WIRE 16 -1 (-3900 2000)(-3475 2000);
WIRE 16 -1 (-3900 2400)(-3475 2400);
WIRE 16 -1 (-3900 2450)(-3475 2450);
WIRE 16 -1 (-3900 2650)(-3475 2650);
WIRE 16 -1 (-3900 2700)(-3475 2700);
WIRE 16 -1 (-3900 2750)(-3475 2750);
WIRE 16 -1 (-3900 2800)(-3475 2800);
WIRE 16 -1 (-3900 2850)(-3475 2850);
WIRE 16 -1 (-3900 2900)(-3475 2900);
WIRE 16 -1 (-3900 3000)(-3475 3000);
WIRE 16 -1 (-3900 3050)(-3475 3050);
WIRE 16 -1 (-3900 2100)(-3475 2100);
WIRE 16 -1 (-3900 2150)(-3475 2150);
WIRE 16 -1 (-3900 2550)(-3475 2550);
WIRE 16 -1 (-3900 2200)(-3475 2200);
WIRE 16 -1 (-3900 2600)(-3475 2600);
WIRE 16 -1 (-3900 2250)(-3475 2250);
WIRE 16 -1 (-3900 2300)(-3475 2300);
WIRE 16 -1 (-3900 2350)(-3475 2350);
WIRE 16 -1 (-3900 3200)(-3475 3200);
WIRE 16 -1 (-3900 3250)(-3475 3250);
WIRE 16 -1 (-3900 3300)(-3475 3300);
WIRE 16 -1 (-3900 3350)(-3475 3350);
WIRE 16 -1 (-3900 3450)(-3475 3450);
WIRE 16 -1 (-3900 3500)(-3475 3500);
WIRE 16 -1 (-3900 3750)(-3475 3750);
WIRE 16 -1 (-3900 3550)(-3475 3550);
WIRE 16 -1 (-3900 3800)(-3475 3800);
WIRE 16 -1 (-3900 3600)(-3475 3600);
WIRE 16 -1 (-3900 3900)(-3475 3900);
WIRE 16 -1 (-3900 3650)(-3475 3650);
WIRE 16 -1 (-3900 3950)(-3475 3950);
WIRE 16 -1 (-3900 3700)(-3475 3700);
WIRE 16 -1 (-3900 3100)(-3475 3100);
WIRE 16 -1 (-3900 4000)(-3475 4000);
WIRE 16 -1 (-3900 3150)(-3475 3150);
WIRE 16 -1 (-3900 4050)(-3475 4050);
WIRE 16 -1 (-3900 4900)(-3475 4900);
WIRE 16 -1 (-3900 4250)(-3475 4250);
WIRE 16 -1 (-3900 4950)(-3475 4950);
WIRE 16 -1 (-3900 4350)(-3475 4350);
WIRE 16 -1 (-3900 4400)(-3475 4400);
WIRE 16 -1 (-3900 5000)(-3475 5000);
WIRE 16 -1 (-3900 5050)(-3475 5050);
WIRE 16 -1 (-3900 4450)(-3475 4450);
WIRE 16 -1 (-3900 5100)(-3475 5100);
WIRE 16 -1 (-3900 4500)(-3475 4500);
WIRE 16 -1 (-3900 4550)(-3475 4550);
WIRE 16 -1 (-3900 4600)(-3475 4600);
WIRE 16 -1 (-3900 4650)(-3475 4650);
WIRE 16 -1 (-3900 4700)(-3475 4700);
WIRE 16 -1 (-3900 4100)(-3475 4100);
WIRE 16 -1 (-3900 4800)(-3475 4800);
WIRE 16 -1 (-3900 4150)(-3475 4150);
WIRE 16 -1 (-3900 4850)(-3475 4850);
WIRE 16 -1 (-3900 4200)(-3475 4200);
WIRE 16 -1 (-3900 6050)(-3475 6050);
WIRE 16 -1 (-3900 5500)(-3475 5500);
WIRE 16 -1 (-3900 5550)(-3475 5550);
WIRE 16 -1 (-3900 5600)(-3475 5600);
WIRE 16 -1 (-3900 5700)(-3475 5700);
WIRE 16 -1 (-3900 5750)(-3475 5750);
WIRE 16 -1 (-3900 5150)(-3475 5150);
WIRE 16 -1 (-3900 5800)(-3475 5800);
WIRE 16 -1 (-3900 5250)(-3475 5250);
WIRE 16 -1 (-3900 5850)(-3475 5850);
WIRE 16 -1 (-3900 5300)(-3475 5300);
WIRE 16 -1 (-3900 5900)(-3475 5900);
WIRE 16 -1 (-3900 5350)(-3475 5350);
WIRE 16 -1 (-3900 5950)(-3475 5950);
WIRE 16 -1 (-3900 5400)(-3475 5400);
WIRE 16 -1 (-3900 6000)(-3475 6000);
WIRE 16 -1 (-3900 5450)(-3475 5450);
QUIT
